FILE_TYPE = MACRO_DRAWING;
SET COLOR_WIRE YELLOW;
SET COLOR_PROP ORANGE;
SET COLOR_DOT WHITE;
SET COLOR_ARC YELLOW;
SET COLOR_BODY GREEN;
SET COLOR_NOTE PURPLE;
SET PROP_DISPLAY VALUE;
SET PAGE_NUMBER P190;
FORCEADD OFFPAGE..3
R 2
(-1700 -100);
FORCEPROP 2 LAST $XR0 183 
J 0
(-2010 -100);
DISPLAY 0.638298 (-2010 -100);
PAINT MONO (-2010 -100);
FORCEPROP 2 LAST CDS_LIB standard
J 0
(-1700 -100);
PAINT MONO (-1700 -100);
DISPLAY INVISIBLE (-1700 -100);
FORCEPROP 1 LAST OFFPAGE TRUE
J 2
(-2025 -225);
DISPLAY 0.872340 (-2025 -225);
DISPLAY INVISIBLE (-2025 -225);
FORCEPROP 1 LAST COMMENT_BODY TRUE
J 2
(-1650 -200);
DISPLAY 0.872340 (-1650 -200);
PAINT GREEN (-1650 -200);
DISPLAY INVISIBLE (-1650 -200);
FORCEPROP 2 LAST PATH I10
J 0
(-1650 -25);
DISPLAY 1.021277 (-1650 -25);
DISPLAY INVISIBLE (-1650 -25);
FORCEADD Q_RES..1
(-650 -250);
FORCEPROP 1 LAST PART_NUMBER CS01002FB07
J 0
(-525 -275);
DISPLAY 0.319149 (-525 -275);
DISPLAY INVISIBLE (-525 -275);
FORCEPROP 1 LAST MATERIAL CHIP
J 0
(-525 -225);
DISPLAY 0.319149 (-525 -225);
FORCEPROP 1 LAST VALUE 10
J 2
(-475 -250);
DISPLAY 0.510638 (-475 -250);
FORCEPROP 1 LAST TOLERANCE 1%
J 0
(-450 -250);
DISPLAY 0.510638 (-450 -250);
FORCEPROP 1 LAST WATTAGE 1/16W
J 2
(-375 -225);
DISPLAY 0.319149 (-375 -225);
FORCEPROP 1 LAST PACK_TYPE 0402LF
J 0
(-375 -250);
DISPLAY 0.510638 (-375 -250);
FORCEPROP 1 LAST LOCATION R1872
J 0
(-875 -250);
DISPLAY 0.638298 (-875 -250);
FORCEPROP 1 LASTPIN (-750 -250) $PN 1
J 0
(-738 -238);
DISPLAY 0.787234 (-738 -238);
PAINT MONO (-738 -238);
FORCEPROP 1 LASTPIN (-550 -250) $PN 2
J 0
(-588 -238);
DISPLAY 0.787234 (-588 -238);
PAINT MONO (-588 -238);
FORCEPROP 2 LAST CDS_LIB pure_quanta
J 0
(-650 -250);
DISPLAY INVISIBLE (-650 -250);
FORCEPROP 1 LAST PATH I100
J 0
(-700 -100);
DISPLAY 0.978723 (-700 -100);
PAINT WHITE (-700 -100);
DISPLAY INVISIBLE (-700 -100);
FORCEPROP 0 LAST $SEC 1
J 0
(-375 -200);
DISPLAY 0.680851 (-375 -200);
PAINT MONO (-375 -200);
DISPLAY INVISIBLE (-375 -200);
FORCEPROP 0 LAST CDS_SEC 1
J 0
(-375 -200);
DISPLAY 1.021277 (-375 -200);
DISPLAY INVISIBLE (-375 -200);
FORCEADD Q_RES..1
(-625 2725);
FORCEPROP 1 LAST PART_NUMBER CS01002FB07
J 0
(-500 2700);
DISPLAY 0.319149 (-500 2700);
DISPLAY INVISIBLE (-500 2700);
FORCEPROP 1 LAST PACK_TYPE 0402LF
J 0
(-350 2725);
DISPLAY 0.510638 (-350 2725);
FORCEPROP 1 LAST VALUE 10
J 2
(-450 2725);
DISPLAY 0.510638 (-450 2725);
FORCEPROP 1 LAST WATTAGE 1/16W
J 2
(-350 2750);
DISPLAY 0.319149 (-350 2750);
FORCEPROP 1 LAST TOLERANCE 1%
J 0
(-425 2725);
DISPLAY 0.510638 (-425 2725);
FORCEPROP 1 LAST MATERIAL CHIP
J 0
(-500 2750);
DISPLAY 0.319149 (-500 2750);
FORCEPROP 1 LAST LOCATION R2363
J 0
(-875 2725);
DISPLAY 0.638298 (-875 2725);
FORCEPROP 1 LASTPIN (-725 2725) $PN 1
J 0
(-713 2737);
DISPLAY 0.787234 (-713 2737);
PAINT MONO (-713 2737);
FORCEPROP 1 LASTPIN (-525 2725) $PN 2
J 0
(-563 2737);
DISPLAY 0.787234 (-563 2737);
PAINT MONO (-563 2737);
FORCEPROP 2 LAST CDS_LIB pure_quanta
J 0
(-625 2725);
DISPLAY INVISIBLE (-625 2725);
FORCEPROP 1 LAST PATH I101
J 0
(-675 2875);
DISPLAY 0.978723 (-675 2875);
PAINT WHITE (-675 2875);
DISPLAY INVISIBLE (-675 2875);
FORCEPROP 0 LAST $SEC 1
J 0
(-350 2775);
DISPLAY 0.680851 (-350 2775);
PAINT MONO (-350 2775);
DISPLAY INVISIBLE (-350 2775);
FORCEPROP 0 LAST CDS_SEC 1
J 0
(-350 2775);
DISPLAY 1.021277 (-350 2775);
DISPLAY INVISIBLE (-350 2775);
FORCEADD Q_RES..1
(-450 225);
FORCEPROP 1 LAST PART_NUMBER CS01002FB07
J 0
(-325 200);
DISPLAY 0.319149 (-325 200);
DISPLAY INVISIBLE (-325 200);
FORCEPROP 1 LAST TOLERANCE 1%
J 0
(-250 225);
DISPLAY 0.510638 (-250 225);
FORCEPROP 1 LAST VALUE 10
J 2
(-275 225);
DISPLAY 0.510638 (-275 225);
FORCEPROP 1 LAST PACK_TYPE 0402LF
J 0
(-175 225);
DISPLAY 0.510638 (-175 225);
FORCEPROP 1 LAST MATERIAL CHIP
J 0
(-325 250);
DISPLAY 0.319149 (-325 250);
FORCEPROP 1 LAST WATTAGE 1/16W
J 2
(-175 250);
DISPLAY 0.319149 (-175 250);
FORCEPROP 1 LAST LOCATION R1479
J 0
(-675 225);
DISPLAY 0.638298 (-675 225);
FORCEPROP 1 LASTPIN (-550 225) $PN 1
J 0
(-538 237);
DISPLAY 0.787234 (-538 237);
PAINT MONO (-538 237);
FORCEPROP 1 LASTPIN (-350 225) $PN 2
J 0
(-388 237);
DISPLAY 0.787234 (-388 237);
PAINT MONO (-388 237);
FORCEPROP 2 LAST CDS_LIB pure_quanta
J 0
(-450 225);
DISPLAY INVISIBLE (-450 225);
FORCEPROP 1 LAST PATH I102
J 0
(-500 375);
DISPLAY 0.978723 (-500 375);
PAINT WHITE (-500 375);
DISPLAY INVISIBLE (-500 375);
FORCEPROP 0 LAST $SEC 1
J 0
(-175 275);
DISPLAY 0.680851 (-175 275);
PAINT MONO (-175 275);
DISPLAY INVISIBLE (-175 275);
FORCEPROP 0 LAST CDS_SEC 1
J 0
(-175 275);
DISPLAY 1.021277 (-175 275);
DISPLAY INVISIBLE (-175 275);
FORCEADD OFFPAGE..3
R 2
(-2000 3800);
FORCEPROP 2 LAST $XR1 204 
J 0
(-2400 3800);
DISPLAY 0.638298 (-2400 3800);
PAINT MONO (-2400 3800);
FORCEPROP 2 LAST $XR0 183 
J 0
(-2280 3800);
DISPLAY 0.638298 (-2280 3800);
PAINT MONO (-2280 3800);
FORCEPROP 2 LAST CDS_LIB standard
J 0
(-2000 3800);
PAINT MONO (-2000 3800);
DISPLAY INVISIBLE (-2000 3800);
FORCEPROP 1 LAST OFFPAGE TRUE
J 2
(-2325 3675);
DISPLAY 0.872340 (-2325 3675);
DISPLAY INVISIBLE (-2325 3675);
FORCEPROP 1 LAST COMMENT_BODY TRUE
J 2
(-1950 3700);
DISPLAY 0.872340 (-1950 3700);
PAINT GREEN (-1950 3700);
DISPLAY INVISIBLE (-1950 3700);
FORCEPROP 2 LAST PATH I103
J 0
(-2300 3850);
DISPLAY 1.021277 (-2300 3850);
DISPLAY INVISIBLE (-2300 3850);
FORCEADD Q_RES..1
(-625 3800);
FORCEPROP 1 LAST PART_NUMBER CS01002FB07
J 0
(-500 3775);
DISPLAY 0.319149 (-500 3775);
DISPLAY INVISIBLE (-500 3775);
FORCEPROP 1 LAST TOLERANCE 1%
J 0
(-425 3800);
DISPLAY 0.510638 (-425 3800);
FORCEPROP 1 LAST WATTAGE 1/16W
J 2
(-350 3825);
DISPLAY 0.319149 (-350 3825);
FORCEPROP 1 LAST PACK_TYPE 0402LF
J 0
(-500 3775);
DISPLAY 0.510638 (-500 3775);
FORCEPROP 1 LAST VALUE 10
J 2
(-450 3800);
DISPLAY 0.510638 (-450 3800);
FORCEPROP 1 LAST MATERIAL CHIP
J 0
(-500 3825);
DISPLAY 0.319149 (-500 3825);
FORCEPROP 1 LAST LOCATION R4118
J 0
(-875 3800);
DISPLAY 0.638298 (-875 3800);
FORCEPROP 1 LASTPIN (-725 3800) $PN 1
J 0
(-713 3812);
DISPLAY 0.787234 (-713 3812);
PAINT MONO (-713 3812);
FORCEPROP 1 LASTPIN (-525 3800) $PN 2
J 0
(-563 3812);
DISPLAY 0.787234 (-563 3812);
PAINT MONO (-563 3812);
FORCEPROP 2 LAST CDS_LIB pure_quanta
J 0
(-625 3800);
DISPLAY INVISIBLE (-625 3800);
FORCEPROP 1 LAST PATH I105
J 0
(-675 3950);
DISPLAY 0.978723 (-675 3950);
PAINT WHITE (-675 3950);
DISPLAY INVISIBLE (-675 3950);
FORCEPROP 0 LAST $SEC 1
J 0
(-350 3850);
DISPLAY 0.680851 (-350 3850);
PAINT MONO (-350 3850);
DISPLAY INVISIBLE (-350 3850);
FORCEPROP 0 LAST CDS_SEC 1
J 0
(-350 3850);
DISPLAY 1.021277 (-350 3850);
DISPLAY INVISIBLE (-350 3850);
FORCEADD OFFPAGE..3
R 2
(-1700 -150);
FORCEPROP 2 LAST $XR0 183 
J 0
(-2010 -150);
DISPLAY 0.638298 (-2010 -150);
PAINT MONO (-2010 -150);
FORCEPROP 2 LAST CDS_LIB standard
J 0
(-1700 -150);
PAINT MONO (-1700 -150);
DISPLAY INVISIBLE (-1700 -150);
FORCEPROP 1 LAST OFFPAGE TRUE
J 2
(-2025 -275);
DISPLAY 0.872340 (-2025 -275);
DISPLAY INVISIBLE (-2025 -275);
FORCEPROP 1 LAST COMMENT_BODY TRUE
J 2
(-1650 -250);
DISPLAY 0.872340 (-1650 -250);
PAINT GREEN (-1650 -250);
DISPLAY INVISIBLE (-1650 -250);
FORCEPROP 2 LAST PATH I11
J 0
(-1650 -75);
DISPLAY 1.021277 (-1650 -75);
DISPLAY INVISIBLE (-1650 -75);
FORCEADD OFFPAGE..3
R 2
(-1700 -200);
FORCEPROP 2 LAST $XR0 183 
J 0
(-2010 -200);
DISPLAY 0.638298 (-2010 -200);
PAINT MONO (-2010 -200);
FORCEPROP 2 LAST CDS_LIB standard
J 0
(-1700 -200);
PAINT MONO (-1700 -200);
DISPLAY INVISIBLE (-1700 -200);
FORCEPROP 1 LAST OFFPAGE TRUE
J 2
(-2025 -325);
DISPLAY 0.872340 (-2025 -325);
DISPLAY INVISIBLE (-2025 -325);
FORCEPROP 1 LAST COMMENT_BODY TRUE
J 2
(-1650 -300);
DISPLAY 0.872340 (-1650 -300);
PAINT GREEN (-1650 -300);
DISPLAY INVISIBLE (-1650 -300);
FORCEPROP 2 LAST PATH I12
J 0
(-1650 -125);
DISPLAY 1.021277 (-1650 -125);
DISPLAY INVISIBLE (-1650 -125);
FORCEADD OFFPAGE..1
(-1700 -250);
FORCEPROP 2 LAST $XR0 183 
J 0
(-1982 -250);
DISPLAY 0.638298 (-1982 -250);
PAINT MONO (-1982 -250);
FORCEPROP 2 LAST CDS_LIB standard
J 0
(-1700 -250);
PAINT MONO (-1700 -250);
DISPLAY INVISIBLE (-1700 -250);
FORCEPROP 1 LAST OFFPAGE TRUE
J 0
(-1375 -375);
DISPLAY 0.872340 (-1375 -375);
DISPLAY INVISIBLE (-1375 -375);
FORCEPROP 1 LAST COMMENT_BODY TRUE
J 0
(-1575 -350);
DISPLAY 0.872340 (-1575 -350);
PAINT GREEN (-1575 -350);
DISPLAY INVISIBLE (-1575 -350);
FORCEPROP 2 LAST PATH I14
J 0
(-1650 -175);
DISPLAY 1.021277 (-1650 -175);
DISPLAY INVISIBLE (-1650 -175);
FORCEADD OFFPAGE..2
(3775 -250);
FORCEPROP 2 LAST $XR0 240 
J 0
(3994 -250);
DISPLAY 0.638298 (3994 -250);
PAINT MONO (3994 -250);
FORCEPROP 2 LAST CDS_LIB standard
J 0
(3775 -250);
PAINT MONO (3775 -250);
DISPLAY INVISIBLE (3775 -250);
FORCEPROP 1 LAST OFFPAGE TRUE
J 0
(4100 -375);
DISPLAY 0.872340 (4100 -375);
DISPLAY INVISIBLE (4100 -375);
FORCEPROP 1 LAST COMMENT_BODY TRUE
J 0
(3730 -345);
DISPLAY 0.872340 (3730 -345);
PAINT GREEN (3730 -345);
DISPLAY INVISIBLE (3730 -345);
FORCEPROP 2 LAST PATH I15
J 0
(3975 -200);
DISPLAY 1.021277 (3975 -200);
DISPLAY INVISIBLE (3975 -200);
FORCEADD OFFPAGE..2
R 2
(-2000 3900);
FORCEPROP 2 LAST $XR1 183 
J 0
(-2375 3900);
DISPLAY 0.638298 (-2375 3900);
PAINT MONO (-2375 3900);
FORCEPROP 2 LAST $XR0 204 
J 0
(-2255 3900);
DISPLAY 0.638298 (-2255 3900);
PAINT MONO (-2255 3900);
FORCEPROP 2 LAST CDS_LIB standard
J 0
(-2000 3900);
PAINT MONO (-2000 3900);
DISPLAY INVISIBLE (-2000 3900);
FORCEPROP 1 LAST OFFPAGE TRUE
J 2
(-2325 3775);
DISPLAY 0.872340 (-2325 3775);
DISPLAY INVISIBLE (-2325 3775);
FORCEPROP 1 LAST COMMENT_BODY TRUE
J 2
(-1955 3805);
DISPLAY 0.872340 (-1955 3805);
PAINT GREEN (-1955 3805);
DISPLAY INVISIBLE (-1955 3805);
FORCEPROP 2 LAST PATH I18
J 0
(-2275 3950);
DISPLAY 1.021277 (-2275 3950);
DISPLAY INVISIBLE (-2275 3950);
FORCEADD UNIVERSAL_GND..1
(625 3500);
FORCEPROP 3 LASTPIN (625 3550) SIG_NAME GND\g
J 0
(635 3560);
DISPLAY 0.659574 (635 3560);
PAINT MONO (635 3560);
DISPLAY INVISIBLE (635 3560);
FORCEPROP 2 LAST CDS_LIB logical_power
J 0
(625 3500);
PAINT MONO (625 3500);
DISPLAY INVISIBLE (625 3500);
FORCEPROP 1 LAST HDL_POWER GND
J 1
(650 3425);
DISPLAY 0.872340 (650 3425);
PAINT GREEN (650 3425);
DISPLAY INVISIBLE (650 3425);
FORCEPROP 1 LAST PATH I20
J 0
(700 3500);
DISPLAY 0.872340 (700 3500);
PAINT AQUA (700 3500);
DISPLAY INVISIBLE (700 3500);
FORCEADD UNIVERSAL_GND..1
(1875 4025);
FORCEPROP 3 LASTPIN (1875 4075) SIG_NAME GND\g
J 0
(1885 4085);
DISPLAY 0.659574 (1885 4085);
PAINT MONO (1885 4085);
DISPLAY INVISIBLE (1885 4085);
FORCEPROP 2 LAST CDS_LIB logical_power
J 0
(1875 4025);
PAINT MONO (1875 4025);
DISPLAY INVISIBLE (1875 4025);
FORCEPROP 1 LAST HDL_POWER GND
J 1
(1900 3950);
DISPLAY 0.872340 (1900 3950);
PAINT GREEN (1900 3950);
DISPLAY INVISIBLE (1900 3950);
FORCEPROP 1 LAST PATH I21
J 0
(1950 4025);
DISPLAY 0.872340 (1950 4025);
PAINT AQUA (1950 4025);
DISPLAY INVISIBLE (1950 4025);
FORCEADD UNIVERSAL_POWER..1
(1400 4650);
FORCEPROP 3 LASTPIN (1400 4600) SIG_NAME PGPPA_AUX\g
J 0
(1410 4610);
DISPLAY 0.659574 (1410 4610);
PAINT MONO (1410 4610);
DISPLAY INVISIBLE (1410 4610);
FORCEPROP 1 LAST HDL_POWER PGPPA_AUX
J 1
(1400 4700);
DISPLAY 0.872340 (1400 4700);
PAINT GREEN (1400 4700);
FORCEPROP 2 LAST CDS_LIB logical_power
J 0
(1400 4650);
PAINT MONO (1400 4650);
DISPLAY INVISIBLE (1400 4650);
FORCEPROP 1 LAST PATH I24
J 0
(1450 4675);
DISPLAY 0.872340 (1450 4675);
PAINT AQUA (1450 4675);
DISPLAY INVISIBLE (1450 4675);
FORCEADD OFFPAGE..3
(4500 3800);
FORCEPROP 2 LAST $XR0 240 
J 0
(4714 3800);
DISPLAY 0.638298 (4714 3800);
PAINT MONO (4714 3800);
FORCEPROP 2 LAST CDS_LIB standard
J 0
(4500 3800);
PAINT MONO (4500 3800);
DISPLAY INVISIBLE (4500 3800);
FORCEPROP 1 LAST OFFPAGE TRUE
J 0
(4825 3675);
DISPLAY 0.872340 (4825 3675);
PAINT GREEN (4825 3675);
DISPLAY INVISIBLE (4825 3675);
FORCEPROP 1 LAST COMMENT_BODY TRUE
J 0
(4450 3700);
DISPLAY 0.872340 (4450 3700);
PAINT GREEN (4450 3700);
DISPLAY INVISIBLE (4450 3700);
FORCEPROP 2 LAST PATH I32
J 0
(4725 3850);
DISPLAY 1.021277 (4725 3850);
DISPLAY INVISIBLE (4725 3850);
FORCEADD Q_RES..1
(-625 3900);
FORCEPROP 1 LAST PART_NUMBER CS00002JB13
J 0
(-725 3950);
DISPLAY 0.404255 (-725 3950);
DISPLAY INVISIBLE (-725 3950);
FORCEPROP 1 LAST TOLERANCE 5%
J 0
(-450 3900);
DISPLAY 0.510638 (-450 3900);
FORCEPROP 1 LAST MATERIAL CHIP
J 0
(-725 3975);
DISPLAY 0.404255 (-725 3975);
FORCEPROP 1 LAST PACK_TYPE 0402LF
J 0
(-725 4000);
DISPLAY 0.404255 (-725 4000);
FORCEPROP 1 LAST WATTAGE 1/16W
J 2
(-500 3975);
DISPLAY 0.404255 (-500 3975);
FORCEPROP 1 LAST VALUE 0
J 2
(-475 3900);
DISPLAY 0.510638 (-475 3900);
FORCEPROP 1 LAST $LOCATION R1214
J 0
(-850 3900);
DISPLAY 0.638298 (-850 3900);
FORCEPROP 1 LASTPIN (-725 3900) $PN 1
J 0
(-713 3912);
DISPLAY 0.787234 (-713 3912);
FORCEPROP 1 LASTPIN (-525 3900) $PN 2
J 0
(-563 3912);
DISPLAY 0.787234 (-563 3912);
FORCEPROP 2 LAST CDS_LIB pure_quanta
J 0
(-625 3900);
PAINT MONO (-625 3900);
DISPLAY INVISIBLE (-625 3900);
FORCEPROP 1 LAST PATH I33
J 0
(-675 4050);
DISPLAY 0.978723 (-675 4050);
PAINT WHITE (-675 4050);
DISPLAY INVISIBLE (-675 4050);
FORCEPROP 2 LAST CDS_LOCATION R1214
J 0
(-675 4100);
DISPLAY 1.021277 (-675 4100);
DISPLAY INVISIBLE (-675 4100);
FORCEPROP 2 LAST $SEC 1
J 0
(-675 4100);
DISPLAY 0.680851 (-675 4100);
PAINT MONO (-675 4100);
DISPLAY INVISIBLE (-675 4100);
FORCEPROP 2 LAST CDS_SEC 1
J 0
(-675 4100);
DISPLAY 1.021277 (-675 4100);
DISPLAY INVISIBLE (-675 4100);
FORCEADD NC7SB3157..1
(1000 3900);
FORCEPROP 1 LAST PART_NUMBER ALSB3157000
J 0
(873 4060);
DISPLAY 0.723404 (873 4060);
PAINT GREEN (873 4060);
DISPLAY INVISIBLE (873 4060);
FORCEPROP 1 LAST VALUE NC7SB3157P6X
J 0
(873 4220);
DISPLAY 0.723404 (873 4220);
PAINT GREEN (873 4220);
FORCEPROP 1 LAST MATERIAL IC
J 0
(873 3980);
DISPLAY 0.723404 (873 3980);
PAINT GREEN (873 3980);
FORCEPROP 1 LAST $LOCATION U60
J 0
(873 4140);
DISPLAY 0.723404 (873 4140);
PAINT GREEN (873 4140);
FORCEPROP 1 LASTPIN (1300 3800) $PN 4
J 0
(1190 3803);
DISPLAY 0.659574 (1190 3803);
PAINT GREEN (1190 3803);
FORCEPROP 1 LASTPIN (700 3800) $PN 3
J 2
(810 3803);
DISPLAY 0.659574 (810 3803);
PAINT GREEN (810 3803);
FORCEPROP 1 LASTPIN (700 3900) $PN 1
J 2
(810 3903);
DISPLAY 0.659574 (810 3903);
PAINT GREEN (810 3903);
FORCEPROP 1 LASTPIN (700 3850) $PN 2
J 2
(810 3853);
DISPLAY 0.659574 (810 3853);
PAINT GREEN (810 3853);
FORCEPROP 1 LASTPIN (1300 3900) $PN 6
J 0
(1190 3903);
DISPLAY 0.659574 (1190 3903);
PAINT GREEN (1190 3903);
FORCEPROP 1 LASTPIN (1300 3850) $PN 5
J 0
(1190 3853);
DISPLAY 0.659574 (1190 3853);
PAINT GREEN (1190 3853);
FORCEPROP 0 LAST MANUF_PN NC7SB3157P6X
J 0
(825 4275);
DISPLAY 0.808511 (825 4275);
DISPLAY INVISIBLE (825 4275);
FORCEPROP 1 LAST PACK_TYPE SMLF
J 0
(1000 3650);
DISPLAY 0.723404 (1000 3650);
PAINT GREEN (1000 3650);
DISPLAY INVISIBLE (1000 3650);
FORCEPROP 2 LAST SEC_TYPE SMLF
J 0
(875 4425);
DISPLAY 1.021277 (875 4425);
DISPLAY INVISIBLE (875 4425);
FORCEPROP 2 LAST CDS_LIB pure_quanta
J 0
(1000 3900);
PAINT MONO (1000 3900);
DISPLAY INVISIBLE (1000 3900);
FORCEPROP 1 LAST CDS_LMAN_SYM_OUTLINE -150,50,150,-150
J 0
(1000 3900);
DISPLAY 0.468085 (1000 3900);
PAINT GREEN (1000 3900);
DISPLAY INVISIBLE (1000 3900);
FORCEPROP 0 LAST PATH I34
J 0
(875 4375);
DISPLAY 1.021277 (875 4375);
DISPLAY INVISIBLE (875 4375);
FORCEPROP 1 LAST $LOCATION U60
J 2
(875 4425);
DISPLAY 1.021277 (875 4425);
DISPLAY INVISIBLE (875 4425);
FORCEPROP 2 LAST CDS_LOCATION U60
J 0
(875 4425);
DISPLAY 1.021277 (875 4425);
DISPLAY INVISIBLE (875 4425);
FORCEPROP 2 LAST SEC 1
J 2
(875 4425);
DISPLAY 0.680851 (875 4425);
PAINT MONO (875 4425);
DISPLAY INVISIBLE (875 4425);
FORCEADD Q_CAP..1
(1875 4350);
FORCEPROP 1 LAST PART_NUMBER CH4104K1B00
J 0
(1925 4200);
DISPLAY 0.510638 (1925 4200);
DISPLAY INVISIBLE (1925 4200);
FORCEPROP 1 LAST VOLTAGE 25V
J 0
(1925 4350);
DISPLAY 0.510638 (1925 4350);
FORCEPROP 1 LAST TOLERANCE 10%
J 0
(1925 4300);
DISPLAY 0.510638 (1925 4300);
FORCEPROP 1 LAST MATERIAL X7R
J 0
(1925 4250);
DISPLAY 0.510638 (1925 4250);
FORCEPROP 1 LAST VALUE 0.1UF
J 0
(1925 4400);
DISPLAY 0.510638 (1925 4400);
FORCEPROP 1 LAST PACK_TYPE 0402
J 0
(1925 4150);
DISPLAY 0.510638 (1925 4150);
FORCEPROP 1 LAST $LOCATION C607
J 0
(1925 4450);
DISPLAY 0.978723 (1925 4450);
FORCEPROP 1 LASTPIN (1875 4450) $PN 1
J 0
(1885 4430);
DISPLAY 0.787234 (1885 4430);
FORCEPROP 1 LASTPIN (1875 4250) $PN 2
J 0
(1885 4230);
DISPLAY 0.787234 (1885 4230);
FORCEPROP 2 LAST CDS_LIB pure_quanta
J 0
(1875 4350);
PAINT MONO (1875 4350);
DISPLAY INVISIBLE (1875 4350);
FORCEPROP 1 LAST PATH I36
J 0
(1925 4500);
DISPLAY 0.978723 (1925 4500);
PAINT WHITE (1925 4500);
DISPLAY INVISIBLE (1925 4500);
FORCEPROP 1 LAST $LOCATION C607
J 2
(1925 4550);
DISPLAY 1.021277 (1925 4550);
DISPLAY INVISIBLE (1925 4550);
FORCEPROP 2 LAST CDS_LOCATION C607
J 0
(1925 4550);
DISPLAY 1.021277 (1925 4550);
DISPLAY INVISIBLE (1925 4550);
FORCEPROP 2 LAST $SEC 1
J 2
(1925 4550);
DISPLAY 0.680851 (1925 4550);
PAINT MONO (1925 4550);
DISPLAY INVISIBLE (1925 4550);
FORCEPROP 2 LAST CDS_SEC 1
J 2
(1925 4550);
DISPLAY 1.021277 (1925 4550);
DISPLAY INVISIBLE (1925 4550);
FORCEADD Q_CAP..1
(1525 4350);
FORCEPROP 1 LAST PART_NUMBER CH5104KEB02
J 0
(1575 4200);
DISPLAY 0.510638 (1575 4200);
DISPLAY INVISIBLE (1575 4200);
FORCEPROP 1 LAST MATERIAL X6S
J 0
(1575 4250);
DISPLAY 0.510638 (1575 4250);
FORCEPROP 1 LAST TOLERANCE 10%
J 0
(1575 4300);
DISPLAY 0.510638 (1575 4300);
FORCEPROP 1 LAST VALUE 1UF
J 0
(1575 4400);
DISPLAY 0.510638 (1575 4400);
FORCEPROP 1 LAST PACK_TYPE C0402
J 0
(1575 4150);
DISPLAY 0.510638 (1575 4150);
FORCEPROP 1 LAST VOLTAGE 25V
J 0
(1575 4350);
DISPLAY 0.510638 (1575 4350);
FORCEPROP 1 LAST $LOCATION C605
J 0
(1575 4450);
DISPLAY 0.978723 (1575 4450);
FORCEPROP 1 LASTPIN (1525 4450) $PN 1
J 0
(1535 4430);
DISPLAY 0.787234 (1535 4430);
FORCEPROP 1 LASTPIN (1525 4250) $PN 2
J 0
(1535 4230);
DISPLAY 0.787234 (1535 4230);
FORCEPROP 2 LAST CDS_LIB pure_quanta
J 0
(1525 4350);
PAINT MONO (1525 4350);
DISPLAY INVISIBLE (1525 4350);
FORCEPROP 1 LAST PATH I37
J 0
(1575 4500);
DISPLAY 0.978723 (1575 4500);
PAINT WHITE (1575 4500);
DISPLAY INVISIBLE (1575 4500);
FORCEPROP 1 LAST $LOCATION C605
J 2
(1575 4550);
DISPLAY 1.021277 (1575 4550);
DISPLAY INVISIBLE (1575 4550);
FORCEPROP 2 LAST CDS_LOCATION C605
J 0
(1575 4550);
DISPLAY 1.021277 (1575 4550);
DISPLAY INVISIBLE (1575 4550);
FORCEPROP 2 LAST $SEC 1
J 2
(1575 4550);
DISPLAY 0.680851 (1575 4550);
PAINT MONO (1575 4550);
DISPLAY INVISIBLE (1575 4550);
FORCEPROP 2 LAST CDS_SEC 1
J 2
(1575 4550);
DISPLAY 1.021277 (1575 4550);
DISPLAY INVISIBLE (1575 4550);
FORCEADD Q_RES..1
(2800 3800);
FORCEPROP 1 LAST PART_NUMBER CS04992FB07
J 0
(2700 3875);
DISPLAY 0.510638 (2700 3875);
DISPLAY INVISIBLE (2700 3875);
FORCEPROP 1 LAST PACK_TYPE 0402LF
J 0
(2700 3925);
DISPLAY 0.510638 (2700 3925);
FORCEPROP 1 LAST MATERIAL CHIP
J 0
(3100 3800);
DISPLAY 0.510638 (3100 3800);
FORCEPROP 1 LAST WATTAGE 1/16W
J 2
(3000 3925);
DISPLAY 0.510638 (3000 3925);
FORCEPROP 1 LAST VALUE 49.9
J 2
(3025 3800);
DISPLAY 0.510638 (3025 3800);
FORCEPROP 1 LAST TOLERANCE 1%
J 0
(3050 3800);
DISPLAY 0.510638 (3050 3800);
FORCEPROP 1 LAST $LOCATION R1215
J 0
(2550 3800);
DISPLAY 0.787234 (2550 3800);
FORCEPROP 1 LASTPIN (2700 3800) $PN 1
J 0
(2712 3812);
DISPLAY 0.787234 (2712 3812);
FORCEPROP 1 LASTPIN (2900 3800) $PN 2
J 0
(2862 3812);
DISPLAY 0.787234 (2862 3812);
FORCEPROP 2 LAST CDS_LIB pure_quanta
J 0
(2800 3800);
PAINT MONO (2800 3800);
DISPLAY INVISIBLE (2800 3800);
FORCEPROP 1 LAST PATH I38
J 0
(2750 3950);
DISPLAY 0.978723 (2750 3950);
PAINT WHITE (2750 3950);
DISPLAY INVISIBLE (2750 3950);
FORCEPROP 2 LAST CDS_LOCATION R1215
J 0
(2750 4000);
DISPLAY 1.021277 (2750 4000);
DISPLAY INVISIBLE (2750 4000);
FORCEPROP 2 LAST $SEC 1
J 0
(2750 4000);
DISPLAY 0.680851 (2750 4000);
PAINT MONO (2750 4000);
DISPLAY INVISIBLE (2750 4000);
FORCEPROP 2 LAST CDS_SEC 1
J 0
(2750 4000);
DISPLAY 1.021277 (2750 4000);
DISPLAY INVISIBLE (2750 4000);
FORCEADD NC7SB3157..1
(1000 2725);
FORCEPROP 1 LAST PART_NUMBER ALSB3157000
J 0
(873 2885);
DISPLAY 0.723404 (873 2885);
PAINT GREEN (873 2885);
DISPLAY INVISIBLE (873 2885);
FORCEPROP 1 LAST VALUE NC7SB3157P6X
J 0
(873 3045);
DISPLAY 0.723404 (873 3045);
PAINT GREEN (873 3045);
FORCEPROP 1 LAST MATERIAL IC
J 0
(873 2805);
DISPLAY 0.723404 (873 2805);
PAINT GREEN (873 2805);
FORCEPROP 1 LAST $LOCATION U61
J 0
(873 2965);
DISPLAY 0.723404 (873 2965);
PAINT GREEN (873 2965);
FORCEPROP 1 LASTPIN (1300 2625) $PN 4
J 0
(1190 2628);
DISPLAY 0.659574 (1190 2628);
PAINT GREEN (1190 2628);
FORCEPROP 1 LASTPIN (700 2625) $PN 3
J 2
(810 2628);
DISPLAY 0.659574 (810 2628);
PAINT GREEN (810 2628);
FORCEPROP 1 LASTPIN (700 2725) $PN 1
J 2
(810 2728);
DISPLAY 0.659574 (810 2728);
PAINT GREEN (810 2728);
FORCEPROP 1 LASTPIN (700 2675) $PN 2
J 2
(810 2678);
DISPLAY 0.659574 (810 2678);
PAINT GREEN (810 2678);
FORCEPROP 1 LASTPIN (1300 2725) $PN 6
J 0
(1190 2728);
DISPLAY 0.659574 (1190 2728);
PAINT GREEN (1190 2728);
FORCEPROP 1 LASTPIN (1300 2675) $PN 5
J 0
(1190 2678);
DISPLAY 0.659574 (1190 2678);
PAINT GREEN (1190 2678);
FORCEPROP 1 LAST PACK_TYPE SMLF
J 0
(1000 2475);
DISPLAY 0.723404 (1000 2475);
PAINT GREEN (1000 2475);
DISPLAY INVISIBLE (1000 2475);
FORCEPROP 2 LAST SEC_TYPE SMLF
J 0
(875 3250);
DISPLAY 1.021277 (875 3250);
DISPLAY INVISIBLE (875 3250);
FORCEPROP 2 LAST CDS_LIB pure_quanta
J 0
(1000 2725);
PAINT MONO (1000 2725);
DISPLAY INVISIBLE (1000 2725);
FORCEPROP 1 LAST CDS_LMAN_SYM_OUTLINE -150,50,150,-150
J 0
(1000 2725);
DISPLAY 0.468085 (1000 2725);
PAINT GREEN (1000 2725);
DISPLAY INVISIBLE (1000 2725);
FORCEPROP 0 LAST MANUF_PN NC7SB3157P6X
J 0
(825 3100);
DISPLAY 0.808511 (825 3100);
DISPLAY INVISIBLE (825 3100);
FORCEPROP 0 LAST PATH I39
J 0
(825 3150);
DISPLAY 1.021277 (825 3150);
DISPLAY INVISIBLE (825 3150);
FORCEPROP 1 LAST $LOCATION U61
J 2
(875 3250);
DISPLAY 1.021277 (875 3250);
DISPLAY INVISIBLE (875 3250);
FORCEPROP 2 LAST CDS_LOCATION U61
J 0
(825 3200);
DISPLAY 1.021277 (825 3200);
DISPLAY INVISIBLE (825 3200);
FORCEPROP 2 LAST SEC 1
J 2
(875 3250);
DISPLAY 0.680851 (875 3250);
PAINT MONO (875 3250);
DISPLAY INVISIBLE (875 3250);
FORCEADD UNIVERSAL_GND..1
(625 2325);
FORCEPROP 3 LASTPIN (625 2375) SIG_NAME GND\g
J 0
(635 2385);
DISPLAY 0.659574 (635 2385);
PAINT MONO (635 2385);
DISPLAY INVISIBLE (635 2385);
FORCEPROP 2 LAST CDS_LIB logical_power
J 0
(625 2325);
PAINT MONO (625 2325);
DISPLAY INVISIBLE (625 2325);
FORCEPROP 1 LAST HDL_POWER GND
J 1
(650 2250);
DISPLAY 0.872340 (650 2250);
PAINT GREEN (650 2250);
DISPLAY INVISIBLE (650 2250);
FORCEPROP 1 LAST PATH I40
J 0
(700 2325);
DISPLAY 0.872340 (700 2325);
PAINT AQUA (700 2325);
DISPLAY INVISIBLE (700 2325);
FORCEADD OFFPAGE..1
(-575 2625);
FORCEPROP 2 LAST $XR0 223 
J 0
(-857 2625);
DISPLAY 0.638298 (-857 2625);
PAINT MONO (-857 2625);
FORCEPROP 2 LAST CDS_LIB standard
J 0
(-575 2625);
PAINT MONO (-575 2625);
DISPLAY INVISIBLE (-575 2625);
FORCEPROP 1 LAST OFFPAGE TRUE
J 0
(-250 2500);
DISPLAY 0.872340 (-250 2500);
PAINT GREEN (-250 2500);
DISPLAY INVISIBLE (-250 2500);
FORCEPROP 1 LAST COMMENT_BODY TRUE
J 0
(-450 2525);
DISPLAY 0.872340 (-450 2525);
PAINT GREEN (-450 2525);
DISPLAY INVISIBLE (-450 2525);
FORCEPROP 2 LAST PATH I41
J 0
(-525 2700);
DISPLAY 1.021277 (-525 2700);
DISPLAY INVISIBLE (-525 2700);
FORCEADD Q_CAP..1
(1875 3175);
FORCEPROP 1 LAST PART_NUMBER CH4104K1B00
J 0
(1925 3025);
DISPLAY 0.510638 (1925 3025);
DISPLAY INVISIBLE (1925 3025);
FORCEPROP 1 LAST MATERIAL X7R
J 0
(1925 3075);
DISPLAY 0.510638 (1925 3075);
FORCEPROP 1 LAST PACK_TYPE 0402
J 0
(1925 2975);
DISPLAY 0.510638 (1925 2975);
FORCEPROP 1 LAST VALUE 0.1UF
J 0
(1925 3225);
DISPLAY 0.510638 (1925 3225);
FORCEPROP 1 LAST VOLTAGE 25V
J 0
(1925 3175);
DISPLAY 0.510638 (1925 3175);
FORCEPROP 1 LAST TOLERANCE 10%
J 0
(1925 3125);
DISPLAY 0.510638 (1925 3125);
FORCEPROP 1 LAST $LOCATION C608
J 0
(1925 3275);
DISPLAY 0.978723 (1925 3275);
FORCEPROP 1 LASTPIN (1875 3275) $PN 1
J 0
(1885 3255);
DISPLAY 0.787234 (1885 3255);
FORCEPROP 1 LASTPIN (1875 3075) $PN 2
J 0
(1885 3055);
DISPLAY 0.787234 (1885 3055);
FORCEPROP 2 LAST CDS_LIB pure_quanta
J 0
(1875 3175);
PAINT MONO (1875 3175);
DISPLAY INVISIBLE (1875 3175);
FORCEPROP 1 LAST PATH I43
J 0
(1925 3325);
DISPLAY 0.978723 (1925 3325);
PAINT WHITE (1925 3325);
DISPLAY INVISIBLE (1925 3325);
FORCEPROP 1 LAST $LOCATION C608
J 2
(1925 3375);
DISPLAY 1.021277 (1925 3375);
DISPLAY INVISIBLE (1925 3375);
FORCEPROP 2 LAST CDS_LOCATION C608
J 0
(1925 3375);
DISPLAY 1.021277 (1925 3375);
DISPLAY INVISIBLE (1925 3375);
FORCEPROP 2 LAST $SEC 1
J 2
(1925 3375);
DISPLAY 0.680851 (1925 3375);
PAINT MONO (1925 3375);
DISPLAY INVISIBLE (1925 3375);
FORCEPROP 2 LAST CDS_SEC 1
J 2
(1925 3375);
DISPLAY 1.021277 (1925 3375);
DISPLAY INVISIBLE (1925 3375);
FORCEADD UNIVERSAL_POWER..1
(1400 3475);
FORCEPROP 3 LASTPIN (1400 3425) SIG_NAME PGPPA_AUX\g
J 0
(1410 3435);
DISPLAY 0.659574 (1410 3435);
PAINT MONO (1410 3435);
DISPLAY INVISIBLE (1410 3435);
FORCEPROP 1 LAST HDL_POWER PGPPA_AUX
J 1
(1400 3525);
DISPLAY 0.872340 (1400 3525);
PAINT GREEN (1400 3525);
FORCEPROP 2 LAST CDS_LIB logical_power
J 0
(1400 3475);
PAINT MONO (1400 3475);
DISPLAY INVISIBLE (1400 3475);
FORCEPROP 1 LAST PATH I44
J 0
(1450 3500);
DISPLAY 0.872340 (1450 3500);
PAINT AQUA (1450 3500);
DISPLAY INVISIBLE (1450 3500);
FORCEADD Q_CAP..1
(1525 3175);
FORCEPROP 1 LAST PART_NUMBER CH5104KEB02
J 0
(1575 3025);
DISPLAY 0.510638 (1575 3025);
DISPLAY INVISIBLE (1575 3025);
FORCEPROP 1 LAST MATERIAL X6S
J 0
(1575 3075);
DISPLAY 0.510638 (1575 3075);
FORCEPROP 1 LAST VALUE 1UF
J 0
(1575 3225);
DISPLAY 0.510638 (1575 3225);
FORCEPROP 1 LAST PACK_TYPE C0402
J 0
(1575 2975);
DISPLAY 0.510638 (1575 2975);
FORCEPROP 1 LAST VOLTAGE 25V
J 0
(1575 3175);
DISPLAY 0.510638 (1575 3175);
FORCEPROP 1 LAST TOLERANCE 10%
J 0
(1575 3125);
DISPLAY 0.510638 (1575 3125);
FORCEPROP 1 LAST $LOCATION C606
J 0
(1575 3275);
DISPLAY 0.978723 (1575 3275);
FORCEPROP 1 LASTPIN (1525 3275) $PN 1
J 0
(1535 3255);
DISPLAY 0.787234 (1535 3255);
FORCEPROP 1 LASTPIN (1525 3075) $PN 2
J 0
(1535 3055);
DISPLAY 0.787234 (1535 3055);
FORCEPROP 2 LAST CDS_LIB pure_quanta
J 0
(1525 3175);
PAINT MONO (1525 3175);
DISPLAY INVISIBLE (1525 3175);
FORCEPROP 1 LAST PATH I45
J 0
(1575 3325);
DISPLAY 0.978723 (1575 3325);
PAINT WHITE (1575 3325);
DISPLAY INVISIBLE (1575 3325);
FORCEPROP 1 LAST $LOCATION C606
J 2
(1575 3375);
DISPLAY 1.021277 (1575 3375);
DISPLAY INVISIBLE (1575 3375);
FORCEPROP 2 LAST CDS_LOCATION C606
J 0
(1575 3375);
DISPLAY 1.021277 (1575 3375);
DISPLAY INVISIBLE (1575 3375);
FORCEPROP 2 LAST $SEC 1
J 2
(1575 3375);
DISPLAY 0.680851 (1575 3375);
PAINT MONO (1575 3375);
DISPLAY INVISIBLE (1575 3375);
FORCEPROP 2 LAST CDS_SEC 1
J 2
(1575 3375);
DISPLAY 1.021277 (1575 3375);
DISPLAY INVISIBLE (1575 3375);
FORCEADD UNIVERSAL_GND..1
(1875 2850);
FORCEPROP 3 LASTPIN (1875 2900) SIG_NAME GND\g
J 0
(1885 2910);
DISPLAY 0.659574 (1885 2910);
PAINT MONO (1885 2910);
DISPLAY INVISIBLE (1885 2910);
FORCEPROP 2 LAST CDS_LIB logical_power
J 0
(1875 2850);
PAINT MONO (1875 2850);
DISPLAY INVISIBLE (1875 2850);
FORCEPROP 1 LAST HDL_POWER GND
J 1
(1900 2775);
DISPLAY 0.872340 (1900 2775);
PAINT GREEN (1900 2775);
DISPLAY INVISIBLE (1900 2775);
FORCEPROP 1 LAST PATH I46
J 0
(1950 2850);
DISPLAY 0.872340 (1950 2850);
PAINT AQUA (1950 2850);
DISPLAY INVISIBLE (1950 2850);
FORCEADD OFFPAGE..2
(2250 2625);
FORCEPROP 2 LAST $XR0 240 
J 0
(2439 2625);
DISPLAY 0.638298 (2439 2625);
PAINT MONO (2439 2625);
FORCEPROP 2 LAST CDS_LIB standard
J 0
(2250 2625);
PAINT MONO (2250 2625);
DISPLAY INVISIBLE (2250 2625);
FORCEPROP 1 LAST OFFPAGE TRUE
J 0
(2575 2500);
DISPLAY 0.872340 (2575 2500);
DISPLAY INVISIBLE (2575 2500);
FORCEPROP 1 LAST COMMENT_BODY TRUE
J 0
(2205 2530);
DISPLAY 0.872340 (2205 2530);
PAINT GREEN (2205 2530);
DISPLAY INVISIBLE (2205 2530);
FORCEPROP 2 LAST PATH I48
J 0
(2450 2675);
DISPLAY 1.021277 (2450 2675);
DISPLAY INVISIBLE (2450 2675);
FORCEADD OFFPAGE..3
(3775 -50);
FORCEPROP 2 LAST $XR0 240 
J 0
(3989 -50);
DISPLAY 0.638298 (3989 -50);
PAINT MONO (3989 -50);
FORCEPROP 2 LAST CDS_LIB standard
J 0
(3775 -50);
PAINT MONO (3775 -50);
DISPLAY INVISIBLE (3775 -50);
FORCEPROP 1 LAST OFFPAGE TRUE
J 0
(4100 -175);
DISPLAY 0.872340 (4100 -175);
PAINT GREEN (4100 -175);
DISPLAY INVISIBLE (4100 -175);
FORCEPROP 1 LAST COMMENT_BODY TRUE
J 0
(3725 -150);
DISPLAY 0.872340 (3725 -150);
PAINT GREEN (3725 -150);
DISPLAY INVISIBLE (3725 -150);
FORCEPROP 2 LAST PATH I5
J 0
(4000 0);
DISPLAY 1.021277 (4000 0);
DISPLAY INVISIBLE (4000 0);
FORCEADD OFFPAGE..1
(-1725 225);
FORCEPROP 2 LAST $XR0 183 
J 0
(-1977 225);
DISPLAY 0.638298 (-1977 225);
PAINT MONO (-1977 225);
FORCEPROP 2 LAST CDS_LIB standard
J 0
(-1725 225);
PAINT MONO (-1725 225);
DISPLAY INVISIBLE (-1725 225);
FORCEPROP 1 LAST OFFPAGE TRUE
J 0
(-1400 100);
DISPLAY 0.872340 (-1400 100);
DISPLAY INVISIBLE (-1400 100);
FORCEPROP 1 LAST COMMENT_BODY TRUE
J 0
(-1600 125);
DISPLAY 0.872340 (-1600 125);
PAINT GREEN (-1600 125);
DISPLAY INVISIBLE (-1600 125);
FORCEPROP 2 LAST PATH I50
J 0
(-2025 275);
DISPLAY 1.021277 (-2025 275);
DISPLAY INVISIBLE (-2025 275);
FORCEADD OFFPAGE..2
(1250 225);
FORCEPROP 2 LAST $XR0 240 
J 0
(1439 225);
DISPLAY 0.638298 (1439 225);
PAINT MONO (1439 225);
FORCEPROP 2 LAST CDS_LIB standard
J 0
(1250 225);
PAINT MONO (1250 225);
DISPLAY INVISIBLE (1250 225);
FORCEPROP 1 LAST OFFPAGE TRUE
J 0
(1575 100);
DISPLAY 0.872340 (1575 100);
DISPLAY INVISIBLE (1575 100);
FORCEPROP 1 LAST COMMENT_BODY TRUE
J 0
(1205 130);
DISPLAY 0.872340 (1205 130);
PAINT GREEN (1205 130);
DISPLAY INVISIBLE (1205 130);
FORCEPROP 2 LAST PATH I51
J 0
(1450 275);
DISPLAY 1.021277 (1450 275);
DISPLAY INVISIBLE (1450 275);
FORCEADD OFFPAGE..4
(4175 2725);
FORCEPROP 2 LAST $XR1 257 
J 0
(4481 2725);
DISPLAY 0.638298 (4481 2725);
PAINT MONO (4481 2725);
FORCEPROP 2 LAST $XR0 202 
J 0
(4361 2725);
DISPLAY 0.638298 (4361 2725);
PAINT MONO (4361 2725);
FORCEPROP 2 LAST CDS_LIB standard
J 0
(4175 2725);
PAINT MONO (4175 2725);
DISPLAY INVISIBLE (4175 2725);
FORCEPROP 1 LAST OFFPAGE TRUE
J 0
(4500 2600);
DISPLAY 1.170213 (4500 2600);
PAINT GREEN (4500 2600);
DISPLAY INVISIBLE (4500 2600);
FORCEPROP 1 LAST COMMENT_BODY TRUE
J 0
(4150 2625);
DISPLAY 1.170213 (4150 2625);
PAINT GREEN (4150 2625);
DISPLAY INVISIBLE (4150 2625);
FORCEPROP 2 LAST PATH I53
J 0
(4525 2775);
DISPLAY 1.021277 (4525 2775);
DISPLAY INVISIBLE (4525 2775);
FORCEADD Q_RES..1
(2800 2725);
FORCEPROP 1 LAST PART_NUMBER CS00002JB13
J 0
(2700 2775);
DISPLAY 0.510638 (2700 2775);
DISPLAY INVISIBLE (2700 2775);
FORCEPROP 1 LAST VALUE 0
J 2
(2975 2725);
DISPLAY 0.510638 (2975 2725);
FORCEPROP 1 LAST WATTAGE 1/16W
J 2
(3000 2825);
DISPLAY 0.510638 (3000 2825);
FORCEPROP 1 LAST PACK_TYPE 0402LF
J 0
(2700 2825);
DISPLAY 0.510638 (2700 2825);
FORCEPROP 1 LAST MATERIAL CHIP
J 0
(3100 2725);
DISPLAY 0.510638 (3100 2725);
FORCEPROP 1 LAST TOLERANCE 5%
J 0
(3025 2725);
DISPLAY 0.510638 (3025 2725);
FORCEPROP 1 LAST $LOCATION R1748
J 0
(2550 2725);
DISPLAY 0.638298 (2550 2725);
FORCEPROP 1 LASTPIN (2700 2725) $PN 1
J 0
(2712 2737);
DISPLAY 0.787234 (2712 2737);
FORCEPROP 1 LASTPIN (2900 2725) $PN 2
J 0
(2862 2737);
DISPLAY 0.787234 (2862 2737);
FORCEPROP 2 LAST CDS_LIB pure_quanta
J 0
(2800 2725);
PAINT MONO (2800 2725);
DISPLAY INVISIBLE (2800 2725);
FORCEPROP 1 LAST PATH I54
J 0
(2750 2875);
DISPLAY 0.978723 (2750 2875);
PAINT WHITE (2750 2875);
DISPLAY INVISIBLE (2750 2875);
FORCEPROP 2 LAST CDS_LOCATION R1748
J 0
(2750 2925);
DISPLAY 1.021277 (2750 2925);
DISPLAY INVISIBLE (2750 2925);
FORCEPROP 2 LAST $SEC 1
J 0
(2750 2925);
DISPLAY 0.680851 (2750 2925);
PAINT MONO (2750 2925);
DISPLAY INVISIBLE (2750 2925);
FORCEPROP 2 LAST CDS_SEC 1
J 0
(2750 2925);
DISPLAY 1.021277 (2750 2925);
DISPLAY INVISIBLE (2750 2925);
FORCEADD OFFPAGE..3
(3775 -100);
FORCEPROP 2 LAST $XR0 240 
J 0
(3989 -100);
DISPLAY 0.638298 (3989 -100);
PAINT MONO (3989 -100);
FORCEPROP 2 LAST CDS_LIB standard
J 0
(3775 -100);
PAINT MONO (3775 -100);
DISPLAY INVISIBLE (3775 -100);
FORCEPROP 1 LAST OFFPAGE TRUE
J 0
(4100 -225);
DISPLAY 0.872340 (4100 -225);
PAINT GREEN (4100 -225);
DISPLAY INVISIBLE (4100 -225);
FORCEPROP 1 LAST COMMENT_BODY TRUE
J 0
(3725 -200);
DISPLAY 0.872340 (3725 -200);
PAINT GREEN (3725 -200);
DISPLAY INVISIBLE (3725 -200);
FORCEPROP 2 LAST PATH I6
J 0
(4000 -50);
DISPLAY 1.021277 (4000 -50);
DISPLAY INVISIBLE (4000 -50);
FORCEADD OFFPAGE..3
(3775 -150);
FORCEPROP 2 LAST $XR0 240 
J 0
(3989 -150);
DISPLAY 0.638298 (3989 -150);
PAINT MONO (3989 -150);
FORCEPROP 2 LAST CDS_LIB standard
J 0
(3775 -150);
PAINT MONO (3775 -150);
DISPLAY INVISIBLE (3775 -150);
FORCEPROP 1 LAST OFFPAGE TRUE
J 0
(4100 -275);
DISPLAY 0.872340 (4100 -275);
PAINT GREEN (4100 -275);
DISPLAY INVISIBLE (4100 -275);
FORCEPROP 1 LAST COMMENT_BODY TRUE
J 0
(3725 -250);
DISPLAY 0.872340 (3725 -250);
PAINT GREEN (3725 -250);
DISPLAY INVISIBLE (3725 -250);
FORCEPROP 2 LAST PATH I7
J 0
(4000 -100);
DISPLAY 1.021277 (4000 -100);
DISPLAY INVISIBLE (4000 -100);
FORCEADD Q_RES..2
R 2
(-800 550);
FORCEPROP 1 LAST PART_NUMBER CS31002FB08
J 2
(-840 375);
DISPLAY 0.510638 (-840 375);
DISPLAY INVISIBLE (-840 375);
FORCEPROP 1 LAST MATERIAL CHIP
J 2
(-840 475);
DISPLAY 0.510638 (-840 475);
FORCEPROP 1 LAST VALUE 10K
J 2
(-845 625);
DISPLAY 0.510638 (-845 625);
FORCEPROP 1 LAST TOLERANCE 1%
J 2
(-845 575);
DISPLAY 0.510638 (-845 575);
FORCEPROP 1 LAST WATTAGE 1/16W
J 2
(-840 525);
DISPLAY 0.510638 (-840 525);
FORCEPROP 1 LAST PACK_TYPE 0402LF
J 2
(-840 425);
DISPLAY 0.510638 (-840 425);
FORCEPROP 1 LAST $LOCATION R1961
J 2
(-845 675);
DISPLAY 0.978723 (-845 675);
FORCEPROP 1 LASTPIN (-800 650) $PN 1
J 2
(-805 612);
DISPLAY 0.787234 (-805 612);
PAINT MONO (-805 612);
FORCEPROP 1 LASTPIN (-800 450) $PN 2
J 2
(-805 460);
DISPLAY 0.787234 (-805 460);
PAINT MONO (-805 460);
FORCEPROP 2 LAST CDS_LIB pure_quanta
J 2
(-800 550);
DISPLAY INVISIBLE (-800 550);
FORCEPROP 1 LAST PATH I70
J 2
(-850 725);
DISPLAY 0.978723 (-850 725);
PAINT WHITE (-850 725);
DISPLAY INVISIBLE (-850 725);
FORCEPROP 0 LAST CDS_LOCATION R1961
J 0
(-825 725);
DISPLAY 1.021277 (-825 725);
DISPLAY INVISIBLE (-825 725);
FORCEPROP 0 LAST $SEC 1
J 0
(-825 725);
DISPLAY 0.680851 (-825 725);
PAINT MONO (-825 725);
DISPLAY INVISIBLE (-825 725);
FORCEPROP 0 LAST CDS_SEC 1
J 0
(-825 725);
DISPLAY 1.021277 (-825 725);
DISPLAY INVISIBLE (-825 725);
FORCEADD UNIVERSAL_POWER..1
(-800 800);
FORCEPROP 3 LASTPIN (-800 750) SIG_NAME PGPPA_AUX\g
J 0
(-790 760);
DISPLAY 0.659574 (-790 760);
PAINT MONO (-790 760);
DISPLAY INVISIBLE (-790 760);
FORCEPROP 1 LAST HDL_POWER PGPPA_AUX
J 1
(-800 850);
DISPLAY 0.872340 (-800 850);
PAINT GREEN (-800 850);
FORCEPROP 2 LAST CDS_LIB logical_power
J 0
(-800 800);
DISPLAY INVISIBLE (-800 800);
FORCEPROP 1 LAST PATH I71
J 0
(-750 825);
DISPLAY 0.872340 (-750 825);
PAINT AQUA (-750 825);
DISPLAY INVISIBLE (-750 825);
FORCEADD OFFPAGE..1
(-1700 2725);
FORCEPROP 2 LAST $XR0 183 
J 0
(-1982 2725);
DISPLAY 0.638298 (-1982 2725);
PAINT MONO (-1982 2725);
FORCEPROP 2 LAST CDS_LIB standard
J 0
(-1700 2725);
DISPLAY INVISIBLE (-1700 2725);
FORCEPROP 1 LAST OFFPAGE TRUE
J 0
(-1375 2600);
DISPLAY 0.872340 (-1375 2600);
PAINT GREEN (-1375 2600);
DISPLAY INVISIBLE (-1375 2600);
FORCEPROP 1 LAST COMMENT_BODY TRUE
J 0
(-1575 2625);
DISPLAY 0.872340 (-1575 2625);
PAINT GREEN (-1575 2625);
DISPLAY INVISIBLE (-1575 2625);
FORCEPROP 2 LAST PATH I79
J 0
(-2000 2775);
DISPLAY 1.021277 (-2000 2775);
DISPLAY INVISIBLE (-2000 2775);
FORCEADD OFFPAGE..3
(3775 -200);
FORCEPROP 2 LAST $XR0 240 
J 0
(3989 -200);
DISPLAY 0.638298 (3989 -200);
PAINT MONO (3989 -200);
FORCEPROP 2 LAST CDS_LIB standard
J 0
(3775 -200);
PAINT MONO (3775 -200);
DISPLAY INVISIBLE (3775 -200);
FORCEPROP 1 LAST OFFPAGE TRUE
J 0
(4100 -325);
DISPLAY 0.872340 (4100 -325);
PAINT GREEN (4100 -325);
DISPLAY INVISIBLE (4100 -325);
FORCEPROP 1 LAST COMMENT_BODY TRUE
J 0
(3725 -300);
DISPLAY 0.872340 (3725 -300);
PAINT GREEN (3725 -300);
DISPLAY INVISIBLE (3725 -300);
FORCEPROP 2 LAST PATH I8
J 0
(4000 -150);
DISPLAY 1.021277 (4000 -150);
DISPLAY INVISIBLE (4000 -150);
FORCEADD OFFPAGE..1
(-450 1400);
FORCEPROP 2 LAST $XR0 214 
J 0
(-732 1400);
DISPLAY 0.638298 (-732 1400);
PAINT MONO (-732 1400);
FORCEPROP 2 LAST CDS_LIB standard
J 0
(-450 1400);
DISPLAY INVISIBLE (-450 1400);
FORCEPROP 1 LAST OFFPAGE TRUE
J 0
(-125 1275);
DISPLAY 0.872340 (-125 1275);
PAINT GREEN (-125 1275);
DISPLAY INVISIBLE (-125 1275);
FORCEPROP 1 LAST COMMENT_BODY TRUE
J 0
(-325 1300);
DISPLAY 0.872340 (-325 1300);
PAINT GREEN (-325 1300);
DISPLAY INVISIBLE (-325 1300);
FORCEPROP 2 LAST PATH I81
J 0
(-750 1450);
DISPLAY 1.021277 (-750 1450);
DISPLAY INVISIBLE (-750 1450);
FORCEADD OFFPAGE..2
(3300 1400);
FORCEPROP 2 LAST $XR1 257 
J 0
(3609 1400);
DISPLAY 0.638298 (3609 1400);
PAINT MONO (3609 1400);
FORCEPROP 2 LAST $XR0 202 
J 0
(3489 1400);
DISPLAY 0.638298 (3489 1400);
PAINT MONO (3489 1400);
FORCEPROP 2 LAST CDS_LIB standard
J 0
(3300 1400);
DISPLAY INVISIBLE (3300 1400);
FORCEPROP 1 LAST OFFPAGE TRUE
J 0
(3625 1275);
DISPLAY 0.872340 (3625 1275);
DISPLAY INVISIBLE (3625 1275);
FORCEPROP 1 LAST COMMENT_BODY TRUE
J 0
(3255 1305);
DISPLAY 0.872340 (3255 1305);
PAINT GREEN (3255 1305);
DISPLAY INVISIBLE (3255 1305);
FORCEPROP 2 LAST PATH I82
J 0
(3500 1450);
DISPLAY 1.021277 (3500 1450);
DISPLAY INVISIBLE (3500 1450);
FORCEADD UNIVERSAL_GND..1
(1175 1175);
FORCEPROP 3 LASTPIN (1175 1225) SIG_NAME GND\g
J 0
(1185 1235);
DISPLAY 0.659574 (1185 1235);
PAINT MONO (1185 1235);
DISPLAY INVISIBLE (1185 1235);
FORCEPROP 2 LAST CDS_LIB logical_power
J 0
(1175 1175);
DISPLAY INVISIBLE (1175 1175);
FORCEPROP 1 LAST HDL_POWER GND
J 1
(1200 1100);
DISPLAY 0.872340 (1200 1100);
PAINT GREEN (1200 1100);
DISPLAY INVISIBLE (1200 1100);
FORCEPROP 1 LAST PATH I83
J 0
(1250 1175);
DISPLAY 0.872340 (1250 1175);
PAINT AQUA (1250 1175);
DISPLAY INVISIBLE (1250 1175);
FORCEADD Q_CAP..1
R 2
(1050 1750);
FORCEPROP 1 LAST PART_NUMBER CH4104K1B00
J 2
(1000 1600);
DISPLAY 0.510638 (1000 1600);
DISPLAY INVISIBLE (1000 1600);
FORCEPROP 1 LAST TOLERANCE 10%
J 2
(1000 1700);
DISPLAY 0.510638 (1000 1700);
FORCEPROP 1 LAST VOLTAGE 25V
J 2
(1000 1750);
DISPLAY 0.510638 (1000 1750);
FORCEPROP 1 LAST VALUE 0.1UF
J 2
(1000 1800);
DISPLAY 0.510638 (1000 1800);
FORCEPROP 1 LAST MATERIAL X7R
J 2
(1000 1650);
DISPLAY 0.510638 (1000 1650);
FORCEPROP 1 LAST PACK_TYPE 0402
J 2
(1000 1550);
DISPLAY 0.510638 (1000 1550);
FORCEPROP 1 LAST $LOCATION C1647
J 2
(1000 1850);
DISPLAY 0.978723 (1000 1850);
FORCEPROP 1 LASTPIN (1050 1850) $PN 1
J 2
(1040 1830);
DISPLAY 0.787234 (1040 1830);
PAINT MONO (1040 1830);
FORCEPROP 1 LASTPIN (1050 1650) $PN 2
J 2
(1040 1630);
DISPLAY 0.787234 (1040 1630);
PAINT MONO (1040 1630);
FORCEPROP 2 LAST CDS_LIB pure_quanta
J 0
(1050 1750);
DISPLAY INVISIBLE (1050 1750);
FORCEPROP 1 LAST PATH I84
J 2
(1000 1900);
DISPLAY 0.978723 (1000 1900);
PAINT WHITE (1000 1900);
DISPLAY INVISIBLE (1000 1900);
FORCEPROP 0 LAST CDS_LOCATION C1647
J 0
(1000 1900);
DISPLAY 1.021277 (1000 1900);
DISPLAY INVISIBLE (1000 1900);
FORCEPROP 0 LAST $SEC 1
J 0
(1000 1900);
DISPLAY 0.680851 (1000 1900);
PAINT MONO (1000 1900);
DISPLAY INVISIBLE (1000 1900);
FORCEPROP 0 LAST CDS_SEC 1
J 0
(1000 1900);
DISPLAY 1.021277 (1000 1900);
DISPLAY INVISIBLE (1000 1900);
FORCEADD UNIVERSAL_GND..1
(1050 1525);
FORCEPROP 3 LASTPIN (1050 1575) SIG_NAME GND\g
J 0
(1060 1585);
DISPLAY 0.659574 (1060 1585);
PAINT MONO (1060 1585);
DISPLAY INVISIBLE (1060 1585);
FORCEPROP 2 LAST CDS_LIB logical_power
J 0
(1050 1525);
DISPLAY INVISIBLE (1050 1525);
FORCEPROP 1 LAST HDL_POWER GND
J 1
(1075 1450);
DISPLAY 0.872340 (1075 1450);
PAINT GREEN (1075 1450);
DISPLAY INVISIBLE (1075 1450);
FORCEPROP 1 LAST PATH I85
J 0
(1125 1525);
DISPLAY 0.872340 (1125 1525);
PAINT AQUA (1125 1525);
DISPLAY INVISIBLE (1125 1525);
FORCEADD UNIVERSAL_POWER..1
(1050 2075);
FORCEPROP 3 LASTPIN (1050 2025) SIG_NAME P3V3_AUX\g
J 0
(1060 2035);
DISPLAY 0.659574 (1060 2035);
PAINT MONO (1060 2035);
DISPLAY INVISIBLE (1060 2035);
FORCEPROP 1 LAST HDL_POWER P3V3_AUX
J 1
(1050 2125);
DISPLAY 0.872340 (1050 2125);
PAINT GREEN (1050 2125);
FORCEPROP 2 LAST CDS_LIB logical_power
J 0
(1050 2075);
DISPLAY INVISIBLE (1050 2075);
FORCEPROP 1 LAST PATH I86
J 0
(1100 2100);
DISPLAY 0.872340 (1100 2100);
PAINT AQUA (1100 2100);
DISPLAY INVISIBLE (1100 2100);
FORCEADD Q_RES..2
(3000 1675);
FORCEPROP 1 LAST PART_NUMBER CS21002FB06
J 0
(3040 1550);
DISPLAY 0.638298 (3040 1550);
DISPLAY INVISIBLE (3040 1550);
FORCEPROP 1 LAST MATERIAL CHIP
J 0
(3040 1600);
DISPLAY 0.638298 (3040 1600);
FORCEPROP 1 LAST PACK_TYPE 0402LF
J 0
(3040 1500);
DISPLAY 0.638298 (3040 1500);
FORCEPROP 1 LAST WATTAGE 1/16W
J 0
(3040 1650);
DISPLAY 0.638298 (3040 1650);
FORCEPROP 1 LAST TOLERANCE 1%
J 0
(3045 1700);
DISPLAY 0.638298 (3045 1700);
FORCEPROP 1 LAST VALUE 1K
J 0
(3045 1750);
DISPLAY 0.638298 (3045 1750);
FORCEPROP 1 LAST $LOCATION R1750
J 0
(3045 1800);
DISPLAY 0.638298 (3045 1800);
FORCEPROP 1 LASTPIN (3000 1775) $PN 1
J 0
(3005 1737);
DISPLAY 0.787234 (3005 1737);
FORCEPROP 1 LASTPIN (3000 1575) $PN 2
J 0
(3005 1585);
DISPLAY 0.787234 (3005 1585);
FORCEPROP 2 LAST CDS_LIB pure_quanta
J 0
(3000 1675);
PAINT MONO (3000 1675);
DISPLAY INVISIBLE (3000 1675);
FORCEPROP 1 LAST PATH I87
J 0
(3050 1850);
DISPLAY 0.978723 (3050 1850);
PAINT WHITE (3050 1850);
DISPLAY INVISIBLE (3050 1850);
FORCEPROP 2 LAST CDS_LOCATION R1750
J 0
(3050 1900);
DISPLAY 1.021277 (3050 1900);
DISPLAY INVISIBLE (3050 1900);
FORCEPROP 2 LAST $SEC 1
J 0
(3050 1900);
DISPLAY 0.680851 (3050 1900);
PAINT MONO (3050 1900);
DISPLAY INVISIBLE (3050 1900);
FORCEPROP 2 LAST CDS_SEC 1
J 0
(3050 1900);
DISPLAY 1.021277 (3050 1900);
DISPLAY INVISIBLE (3050 1900);
FORCEADD UNIVERSAL_POWER..1
(3000 1950);
FORCEPROP 3 LASTPIN (3000 1900) SIG_NAME PGPPA_AUX\g
J 0
(3010 1910);
DISPLAY 0.659574 (3010 1910);
PAINT MONO (3010 1910);
DISPLAY INVISIBLE (3010 1910);
FORCEPROP 1 LAST HDL_POWER PGPPA_AUX
J 1
(3000 2000);
DISPLAY 0.765957 (3000 2000);
PAINT GREEN (3000 2000);
FORCEPROP 2 LAST CDS_LIB logical_power
J 0
(3000 1950);
PAINT MONO (3000 1950);
DISPLAY INVISIBLE (3000 1950);
FORCEPROP 2 LAST BOM_COST VR_SYSTEM 
J 0
(3000 2050);
DISPLAY 0.680851 (3000 2050);
DISPLAY INVISIBLE (3000 2050);
FORCEPROP 1 LAST PATH I88
J 0
(3050 1975);
DISPLAY 0.872340 (3050 1975);
PAINT AQUA (3050 1975);
DISPLAY INVISIBLE (3050 1975);
FORCEADD Q_RES..2
(575 1150);
FORCEPROP 1 LAST PART_NUMBER CS31002FB08
J 0
(615 1025);
DISPLAY 0.638298 (615 1025);
DISPLAY INVISIBLE (615 1025);
FORCEPROP 1 LAST VALUE 10K
J 0
(620 1225);
DISPLAY 0.638298 (620 1225);
FORCEPROP 1 LAST TOLERANCE 1%
J 0
(620 1175);
DISPLAY 0.638298 (620 1175);
FORCEPROP 1 LAST PACK_TYPE 0402LF
J 0
(615 975);
DISPLAY 0.638298 (615 975);
FORCEPROP 1 LAST WATTAGE 1/16W
J 0
(615 1125);
DISPLAY 0.638298 (615 1125);
FORCEPROP 1 LAST MATERIAL EMPTY
J 0
(615 1075);
DISPLAY 0.638298 (615 1075);
PAINT RED (615 1075);
FORCEPROP 1 LAST $LOCATION R1749
J 0
(620 1275);
DISPLAY 0.638298 (620 1275);
FORCEPROP 1 LASTPIN (575 1250) $PN 1
J 0
(580 1212);
DISPLAY 0.787234 (580 1212);
FORCEPROP 1 LASTPIN (575 1050) $PN 2
J 0
(580 1060);
DISPLAY 0.787234 (580 1060);
FORCEPROP 2 LAST CDS_LIB pure_quanta
J 0
(575 1150);
PAINT MONO (575 1150);
DISPLAY INVISIBLE (575 1150);
FORCEPROP 1 LAST PATH I89
J 0
(625 1325);
DISPLAY 0.978723 (625 1325);
PAINT WHITE (625 1325);
DISPLAY INVISIBLE (625 1325);
FORCEPROP 2 LAST CDS_LOCATION R1749
J 0
(625 1375);
DISPLAY 1.021277 (625 1375);
DISPLAY INVISIBLE (625 1375);
FORCEPROP 2 LAST $SEC 1
J 0
(625 1375);
DISPLAY 0.680851 (625 1375);
PAINT MONO (625 1375);
DISPLAY INVISIBLE (625 1375);
FORCEPROP 2 LAST CDS_SEC 1
J 0
(625 1375);
DISPLAY 1.021277 (625 1375);
DISPLAY INVISIBLE (625 1375);
FORCEADD OFFPAGE..3
R 2
(-1700 -50);
FORCEPROP 2 LAST $XR0 183 
J 0
(-2010 -50);
DISPLAY 0.638298 (-2010 -50);
PAINT MONO (-2010 -50);
FORCEPROP 2 LAST CDS_LIB standard
J 0
(-1700 -50);
PAINT MONO (-1700 -50);
DISPLAY INVISIBLE (-1700 -50);
FORCEPROP 1 LAST OFFPAGE TRUE
J 2
(-2025 -175);
DISPLAY 0.872340 (-2025 -175);
DISPLAY INVISIBLE (-2025 -175);
FORCEPROP 1 LAST COMMENT_BODY TRUE
J 2
(-1650 -150);
DISPLAY 0.872340 (-1650 -150);
PAINT GREEN (-1650 -150);
DISPLAY INVISIBLE (-1650 -150);
FORCEPROP 2 LAST PATH I9
J 0
(-1650 25);
DISPLAY 1.021277 (-1650 25);
DISPLAY INVISIBLE (-1650 25);
FORCEADD UNIVERSAL_GND..1
(575 875);
FORCEPROP 3 LASTPIN (575 925) SIG_NAME GND\g
J 0
(585 935);
DISPLAY 0.659574 (585 935);
PAINT MONO (585 935);
DISPLAY INVISIBLE (585 935);
FORCEPROP 2 LAST CDS_LIB logical_power
J 0
(575 875);
PAINT MONO (575 875);
DISPLAY INVISIBLE (575 875);
FORCEPROP 1 LAST HDL_POWER GND
J 1
(600 800);
DISPLAY 0.872340 (600 800);
PAINT GREEN (600 800);
DISPLAY INVISIBLE (600 800);
FORCEPROP 1 LAST PATH I90
J 0
(650 875);
DISPLAY 0.872340 (650 875);
PAINT AQUA (650 875);
DISPLAY INVISIBLE (650 875);
FORCEADD Q_RES..1
(-100 1075);
FORCEPROP 1 LAST PART_NUMBER CS00002JB13
J 0
(-200 1125);
DISPLAY 0.510638 (-200 1125);
DISPLAY INVISIBLE (-200 1125);
FORCEPROP 1 LAST TOLERANCE 5%
J 0
(125 1075);
DISPLAY 0.510638 (125 1075);
FORCEPROP 1 LAST PACK_TYPE 0402LF
J 0
(-200 1175);
DISPLAY 0.510638 (-200 1175);
FORCEPROP 1 LAST VALUE 0
J 2
(75 1075);
DISPLAY 0.510638 (75 1075);
FORCEPROP 1 LAST WATTAGE 1/16W
J 2
(100 1175);
DISPLAY 0.510638 (100 1175);
FORCEPROP 1 LAST MATERIAL EMPTY
J 0
(200 1075);
DISPLAY 0.510638 (200 1075);
PAINT RED (200 1075);
FORCEPROP 1 LAST $LOCATION R2132
J 0
(-350 1075);
DISPLAY 0.638298 (-350 1075);
FORCEPROP 1 LASTPIN (-200 1075) $PN 1
J 0
(-188 1087);
DISPLAY 0.787234 (-188 1087);
PAINT MONO (-188 1087);
FORCEPROP 1 LASTPIN (0 1075) $PN 2
J 0
(-38 1087);
DISPLAY 0.787234 (-38 1087);
PAINT MONO (-38 1087);
FORCEPROP 2 LAST CDS_LIB pure_quanta
J 0
(-100 1075);
DISPLAY INVISIBLE (-100 1075);
FORCEPROP 1 LAST PATH I91
J 0
(-150 1225);
DISPLAY 0.978723 (-150 1225);
PAINT WHITE (-150 1225);
DISPLAY INVISIBLE (-150 1225);
FORCEPROP 0 LAST CDS_LOCATION R2132
J 0
(100 1200);
DISPLAY 1.021277 (100 1200);
DISPLAY INVISIBLE (100 1200);
FORCEPROP 0 LAST $SEC 1
J 0
(100 1200);
DISPLAY 0.680851 (100 1200);
PAINT MONO (100 1200);
DISPLAY INVISIBLE (100 1200);
FORCEPROP 0 LAST CDS_SEC 1
J 0
(100 1200);
DISPLAY 1.021277 (100 1200);
DISPLAY INVISIBLE (100 1200);
FORCEADD OFFPAGE..1
(-1200 1075);
FORCEPROP 2 LAST $XR2 131 
J 0
(-1692 1075);
DISPLAY 0.638298 (-1692 1075);
PAINT MONO (-1692 1075);
FORCEPROP 2 LAST $XR1 201 
J 0
(-1572 1075);
DISPLAY 0.638298 (-1572 1075);
PAINT MONO (-1572 1075);
FORCEPROP 2 LAST $XR0 183 
J 0
(-1452 1075);
DISPLAY 0.638298 (-1452 1075);
PAINT MONO (-1452 1075);
FORCEPROP 2 LAST CDS_LIB standard
J 0
(-1200 1075);
DISPLAY INVISIBLE (-1200 1075);
FORCEPROP 1 LAST OFFPAGE TRUE
J 0
(-875 950);
DISPLAY 0.872340 (-875 950);
PAINT GREEN (-875 950);
DISPLAY INVISIBLE (-875 950);
FORCEPROP 1 LAST COMMENT_BODY TRUE
J 0
(-1075 975);
DISPLAY 0.872340 (-1075 975);
PAINT GREEN (-1075 975);
DISPLAY INVISIBLE (-1075 975);
FORCEPROP 2 LAST PATH I92
J 0
(-1500 1125);
DISPLAY 1.021277 (-1500 1125);
DISPLAY INVISIBLE (-1500 1125);
FORCEADD UNIVERSAL_POWER..1
(25 1950);
FORCEPROP 3 LASTPIN (25 1900) SIG_NAME P3V3_AUX\g
J 0
(35 1910);
DISPLAY 0.659574 (35 1910);
PAINT MONO (35 1910);
DISPLAY INVISIBLE (35 1910);
FORCEPROP 1 LAST HDL_POWER P3V3_AUX
J 1
(25 2000);
DISPLAY 0.617021 (25 2000);
PAINT GREEN (25 2000);
FORCEPROP 2 LAST CDS_LIB logical_power
J 0
(25 1950);
DISPLAY INVISIBLE (25 1950);
FORCEPROP 2 LAST BOM_COST VR_SYSTEM 
J 0
(25 2050);
DISPLAY 0.680851 (25 2050);
DISPLAY INVISIBLE (25 2050);
FORCEPROP 1 LAST PATH I93
J 0
(75 1975);
DISPLAY 0.872340 (75 1975);
PAINT AQUA (75 1975);
DISPLAY INVISIBLE (75 1975);
FORCEADD Q_RES..2
(25 1675);
FORCEPROP 1 LAST PART_NUMBER CS31002FB08
J 0
(65 1550);
DISPLAY 0.510638 (65 1550);
DISPLAY INVISIBLE (65 1550);
FORCEPROP 1 LAST PACK_TYPE 0402LF
J 0
(65 1500);
DISPLAY 0.510638 (65 1500);
FORCEPROP 1 LAST MATERIAL EMPTY
J 0
(65 1600);
DISPLAY 0.510638 (65 1600);
PAINT RED (65 1600);
FORCEPROP 1 LAST VALUE 10K
J 0
(70 1750);
DISPLAY 0.510638 (70 1750);
FORCEPROP 1 LAST TOLERANCE 1%
J 0
(70 1700);
DISPLAY 0.510638 (70 1700);
FORCEPROP 1 LAST WATTAGE 1/16W
J 0
(65 1650);
DISPLAY 0.510638 (65 1650);
FORCEPROP 1 LAST $LOCATION R2451
J 0
(70 1800);
DISPLAY 0.978723 (70 1800);
FORCEPROP 1 LASTPIN (25 1775) $PN 1
J 0
(30 1737);
DISPLAY 0.787234 (30 1737);
PAINT MONO (30 1737);
FORCEPROP 1 LASTPIN (25 1575) $PN 2
J 0
(30 1585);
DISPLAY 0.787234 (30 1585);
PAINT MONO (30 1585);
FORCEPROP 2 LAST CDS_LIB pure_quanta
J 0
(25 1675);
DISPLAY INVISIBLE (25 1675);
FORCEPROP 1 LAST PATH I94
J 0
(75 1850);
DISPLAY 0.978723 (75 1850);
PAINT WHITE (75 1850);
DISPLAY INVISIBLE (75 1850);
FORCEPROP 0 LAST CDS_LOCATION R2451
J 0
(75 1850);
DISPLAY 1.021277 (75 1850);
DISPLAY INVISIBLE (75 1850);
FORCEPROP 0 LAST $SEC 1
J 0
(75 1850);
DISPLAY 0.680851 (75 1850);
PAINT MONO (75 1850);
DISPLAY INVISIBLE (75 1850);
FORCEPROP 0 LAST CDS_SEC 1
J 0
(75 1850);
DISPLAY 1.021277 (75 1850);
DISPLAY INVISIBLE (75 1850);
FORCEADD 74LVC1G07SE7..1
(1700 1400);
FORCEPROP 1 LAST PART_NUMBER AL1G07SE000
J 0
(1550 1625);
DISPLAY 0.723404 (1550 1625);
PAINT GREEN (1550 1625);
DISPLAY INVISIBLE (1550 1625);
FORCEPROP 1 LAST MATERIAL IC
J 0
(1556 1557);
DISPLAY 0.723404 (1556 1557);
PAINT GREEN (1556 1557);
FORCEPROP 2 LAST PART_TYPE SMLF
J 0
(1550 1725);
DISPLAY 0.638298 (1550 1725);
FORCEPROP 2 LAST VALUE 74LVC1G07SE-7
J 0
(1550 1675);
DISPLAY 0.638298 (1550 1675);
FORCEPROP 1 LAST LOCATION U154
J 0
(1550 1775);
DISPLAY 0.723404 (1550 1775);
PAINT GREEN (1550 1775);
FORCEPROP 0 LASTPIN (1400 1400) $PN 2
J 2
(1390 1410);
DISPLAY 0.680851 (1390 1410);
PAINT MONO (1390 1410);
FORCEPROP 0 LASTPIN (1400 1300) $PN 3
J 2
(1390 1310);
DISPLAY 0.680851 (1390 1310);
PAINT MONO (1390 1310);
FORCEPROP 0 LASTPIN (2000 1300) $PN 1
J 0
(2010 1310);
DISPLAY 0.680851 (2010 1310);
PAINT MONO (2010 1310);
FORCEPROP 0 LASTPIN (1400 1500) $PN 5
J 2
(1390 1510);
DISPLAY 0.680851 (1390 1510);
PAINT MONO (1390 1510);
FORCEPROP 0 LASTPIN (2000 1400) $PN 4
J 0
(2010 1410);
DISPLAY 0.680851 (2010 1410);
PAINT MONO (2010 1410);
FORCEPROP 1 LAST NEEDS_NO_SIZE TRUE
J 0
(1700 1400);
DISPLAY 0.723404 (1700 1400);
PAINT GREEN (1700 1400);
DISPLAY INVISIBLE (1700 1400);
FORCEPROP 1 LAST CDS_LMAN_SYM_OUTLINE -150,150,150,-150
J 0
(1700 1400);
DISPLAY 0.468085 (1700 1400);
PAINT GREEN (1700 1400);
DISPLAY INVISIBLE (1700 1400);
FORCEPROP 2 LAST CDS_LIB pure_quanta
J 0
(1700 1400);
DISPLAY INVISIBLE (1700 1400);
FORCEPROP 1 LAST PATH I95
J 0
(1700 1400);
DISPLAY 0.723404 (1700 1400);
PAINT GREEN (1700 1400);
DISPLAY INVISIBLE (1700 1400);
FORCEPROP 0 LAST $SEC 1
J 0
(1550 1825);
DISPLAY 0.680851 (1550 1825);
PAINT MONO (1550 1825);
DISPLAY INVISIBLE (1550 1825);
FORCEPROP 0 LAST CDS_SEC 1
J 0
(1550 1825);
DISPLAY 1.021277 (1550 1825);
DISPLAY INVISIBLE (1550 1825);
FORCEADD Q_RES..1
(-650 -50);
FORCEPROP 1 LAST PART_NUMBER CS01002FB07
J 0
(-525 -75);
DISPLAY 0.319149 (-525 -75);
DISPLAY INVISIBLE (-525 -75);
FORCEPROP 1 LAST VALUE 10
J 2
(-475 -50);
DISPLAY 0.510638 (-475 -50);
FORCEPROP 1 LAST MATERIAL CHIP
J 0
(-525 -25);
DISPLAY 0.319149 (-525 -25);
FORCEPROP 1 LAST TOLERANCE 1%
J 0
(-450 -50);
DISPLAY 0.510638 (-450 -50);
FORCEPROP 1 LAST WATTAGE 1/16W
J 2
(-375 -25);
DISPLAY 0.319149 (-375 -25);
FORCEPROP 1 LAST PACK_TYPE 0402LF
J 0
(-375 -50);
DISPLAY 0.510638 (-375 -50);
FORCEPROP 1 LAST LOCATION R1868
J 0
(-875 -50);
DISPLAY 0.638298 (-875 -50);
FORCEPROP 1 LASTPIN (-750 -50) $PN 1
J 0
(-738 -38);
DISPLAY 0.787234 (-738 -38);
PAINT MONO (-738 -38);
FORCEPROP 1 LASTPIN (-550 -50) $PN 2
J 0
(-588 -38);
DISPLAY 0.787234 (-588 -38);
PAINT MONO (-588 -38);
FORCEPROP 2 LAST CDS_LIB pure_quanta
J 0
(-650 -50);
DISPLAY INVISIBLE (-650 -50);
FORCEPROP 1 LAST PATH I96
J 0
(-700 100);
DISPLAY 0.978723 (-700 100);
PAINT WHITE (-700 100);
DISPLAY INVISIBLE (-700 100);
FORCEPROP 0 LAST $SEC 1
J 0
(-375 0);
DISPLAY 0.680851 (-375 0);
PAINT MONO (-375 0);
DISPLAY INVISIBLE (-375 0);
FORCEPROP 0 LAST CDS_SEC 1
J 0
(-375 0);
DISPLAY 1.021277 (-375 0);
DISPLAY INVISIBLE (-375 0);
FORCEADD Q_RES..1
(-650 -100);
FORCEPROP 1 LAST PART_NUMBER CS01002FB07
J 0
(-525 -125);
DISPLAY 0.319149 (-525 -125);
DISPLAY INVISIBLE (-525 -125);
FORCEPROP 1 LAST TOLERANCE 1%
J 0
(-450 -100);
DISPLAY 0.510638 (-450 -100);
FORCEPROP 1 LAST VALUE 10
J 2
(-475 -100);
DISPLAY 0.510638 (-475 -100);
FORCEPROP 1 LAST MATERIAL CHIP
J 0
(-525 -75);
DISPLAY 0.319149 (-525 -75);
FORCEPROP 1 LAST WATTAGE 1/16W
J 2
(-375 -75);
DISPLAY 0.319149 (-375 -75);
FORCEPROP 1 LAST PACK_TYPE 0402LF
J 0
(-375 -100);
DISPLAY 0.510638 (-375 -100);
FORCEPROP 1 LAST LOCATION R1869
J 0
(-875 -100);
DISPLAY 0.638298 (-875 -100);
FORCEPROP 1 LASTPIN (-750 -100) $PN 1
J 0
(-738 -88);
DISPLAY 0.787234 (-738 -88);
PAINT MONO (-738 -88);
FORCEPROP 1 LASTPIN (-550 -100) $PN 2
J 0
(-588 -88);
DISPLAY 0.787234 (-588 -88);
PAINT MONO (-588 -88);
FORCEPROP 2 LAST CDS_LIB pure_quanta
J 0
(-650 -100);
DISPLAY INVISIBLE (-650 -100);
FORCEPROP 1 LAST PATH I97
J 0
(-700 50);
DISPLAY 0.978723 (-700 50);
PAINT WHITE (-700 50);
DISPLAY INVISIBLE (-700 50);
FORCEPROP 0 LAST $SEC 1
J 0
(-375 -50);
DISPLAY 0.680851 (-375 -50);
PAINT MONO (-375 -50);
DISPLAY INVISIBLE (-375 -50);
FORCEPROP 0 LAST CDS_SEC 1
J 0
(-375 -50);
DISPLAY 1.021277 (-375 -50);
DISPLAY INVISIBLE (-375 -50);
FORCEADD Q_RES..1
(-650 -150);
FORCEPROP 1 LAST PART_NUMBER CS01002FB07
J 0
(-525 -175);
DISPLAY 0.319149 (-525 -175);
DISPLAY INVISIBLE (-525 -175);
FORCEPROP 1 LAST WATTAGE 1/16W
J 2
(-375 -125);
DISPLAY 0.319149 (-375 -125);
FORCEPROP 1 LAST PACK_TYPE 0402LF
J 0
(-375 -150);
DISPLAY 0.510638 (-375 -150);
FORCEPROP 1 LAST VALUE 10
J 2
(-475 -150);
DISPLAY 0.510638 (-475 -150);
FORCEPROP 1 LAST MATERIAL CHIP
J 0
(-525 -125);
DISPLAY 0.319149 (-525 -125);
FORCEPROP 1 LAST TOLERANCE 1%
J 0
(-450 -150);
DISPLAY 0.510638 (-450 -150);
FORCEPROP 1 LAST LOCATION R1870
J 0
(-875 -150);
DISPLAY 0.638298 (-875 -150);
FORCEPROP 1 LASTPIN (-750 -150) $PN 1
J 0
(-738 -138);
DISPLAY 0.787234 (-738 -138);
PAINT MONO (-738 -138);
FORCEPROP 1 LASTPIN (-550 -150) $PN 2
J 0
(-588 -138);
DISPLAY 0.787234 (-588 -138);
PAINT MONO (-588 -138);
FORCEPROP 2 LAST CDS_LIB pure_quanta
J 0
(-650 -150);
DISPLAY INVISIBLE (-650 -150);
FORCEPROP 1 LAST PATH I98
J 0
(-700 0);
DISPLAY 0.978723 (-700 0);
PAINT WHITE (-700 0);
DISPLAY INVISIBLE (-700 0);
FORCEPROP 0 LAST $SEC 1
J 0
(-375 -100);
DISPLAY 0.680851 (-375 -100);
PAINT MONO (-375 -100);
DISPLAY INVISIBLE (-375 -100);
FORCEPROP 0 LAST CDS_SEC 1
J 0
(-375 -100);
DISPLAY 1.021277 (-375 -100);
DISPLAY INVISIBLE (-375 -100);
FORCEADD Q_RES..1
(-650 -200);
FORCEPROP 1 LAST PART_NUMBER CS01002FB07
J 0
(-525 -225);
DISPLAY 0.319149 (-525 -225);
DISPLAY INVISIBLE (-525 -225);
FORCEPROP 1 LAST MATERIAL CHIP
J 0
(-525 -175);
DISPLAY 0.319149 (-525 -175);
FORCEPROP 1 LAST VALUE 10
J 2
(-475 -200);
DISPLAY 0.510638 (-475 -200);
FORCEPROP 1 LAST WATTAGE 1/16W
J 2
(-375 -175);
DISPLAY 0.319149 (-375 -175);
FORCEPROP 1 LAST TOLERANCE 1%
J 0
(-450 -200);
DISPLAY 0.510638 (-450 -200);
FORCEPROP 1 LAST PACK_TYPE 0402LF
J 0
(-375 -200);
DISPLAY 0.510638 (-375 -200);
FORCEPROP 1 LAST LOCATION R1871
J 0
(-875 -200);
DISPLAY 0.638298 (-875 -200);
FORCEPROP 1 LASTPIN (-750 -200) $PN 1
J 0
(-738 -188);
DISPLAY 0.787234 (-738 -188);
PAINT MONO (-738 -188);
FORCEPROP 1 LASTPIN (-550 -200) $PN 2
J 0
(-588 -188);
DISPLAY 0.787234 (-588 -188);
PAINT MONO (-588 -188);
FORCEPROP 2 LAST CDS_LIB pure_quanta
J 0
(-650 -200);
DISPLAY INVISIBLE (-650 -200);
FORCEPROP 1 LAST PATH I99
J 0
(-700 -50);
DISPLAY 0.978723 (-700 -50);
PAINT WHITE (-700 -50);
DISPLAY INVISIBLE (-700 -50);
FORCEPROP 0 LAST $SEC 1
J 0
(-375 -150);
DISPLAY 0.680851 (-375 -150);
PAINT MONO (-375 -150);
DISPLAY INVISIBLE (-375 -150);
FORCEPROP 0 LAST CDS_SEC 1
J 0
(-375 -150);
DISPLAY 1.021277 (-375 -150);
DISPLAY INVISIBLE (-375 -150);
FORCEADD DNS..1
(575 1125);
PAINT RED (575 1125);
FORCEPROP 2 LAST CDS_LIB mstr_misc
J 0
(575 1125);
PAINT MONO (575 1125);
DISPLAY INVISIBLE (575 1125);
FORCEPROP 2 LAST BOM_COST VR_SYSTEM 
J 0
(400 1300);
DISPLAY 0.680851 (400 1300);
DISPLAY INVISIBLE (400 1300);
FORCEPROP 1 LAST COMMENT_BODY TRUE
R 1
J 0
(650 900);
DISPLAY 0.872340 (650 900);
PAINT GREEN (650 900);
DISPLAY INVISIBLE (650 900);
FORCEADD DNS..1
(25 1650);
PAINT RED (25 1650);
FORCEPROP 2 LAST CDS_LIB mstr_misc
J 0
(25 1650);
DISPLAY INVISIBLE (25 1650);
FORCEPROP 2 LAST BOM_COST VR_SYSTEM 
J 0
(-150 1825);
DISPLAY 0.680851 (-150 1825);
DISPLAY INVISIBLE (-150 1825);
FORCEPROP 1 LAST COMMENT_BODY TRUE
R 1
J 0
(100 1425);
DISPLAY 0.872340 (100 1425);
PAINT GREEN (100 1425);
DISPLAY INVISIBLE (100 1425);
FORCEADD DNS..1
(-75 1075);
PAINT RED (-75 1075);
FORCEPROP 2 LAST BOM_COST VR_SYSTEM 
J 0
(-250 1250);
DISPLAY 0.680851 (-250 1250);
DISPLAY INVISIBLE (-250 1250);
FORCEPROP 2 LAST CDS_LIB mstr_misc
J 0
(-75 1075);
DISPLAY INVISIBLE (-75 1075);
FORCEPROP 1 LAST COMMENT_BODY TRUE
R 1
J 0
(0 850);
DISPLAY 0.872340 (0 850);
PAINT GREEN (0 850);
DISPLAY INVISIBLE (0 850);
FORCEADD DESIGN_NOTE..1
(4400 3375);
FORCEPROP 0 LAST L1 ESPI OR LPC ENABLE SELECTION
J 0
(4200 3250);
DISPLAY 0.808511 (4200 3250);
PAINT YELLOW (4200 3250);
FORCEPROP 0 LAST L2 0: LPC
J 0
(4200 3175);
DISPLAY 0.808511 (4200 3175);
PAINT YELLOW (4200 3175);
FORCEPROP 0 LAST L3 1: ESPI
J 0
(4200 3100);
DISPLAY 0.808511 (4200 3100);
PAINT YELLOW (4200 3100);
FORCEPROP 2 LAST CDS_LIB logical_power
J 0
(4400 3375);
DISPLAY INVISIBLE (4400 3375);
FORCEPROP 1 LAST COMMENT_BODY TRUE
J 0
(4425 3475);
DISPLAY 0.978723 (4425 3475);
DISPLAY INVISIBLE (4425 3475);
FORCEADD QUANTA_TITLE_BLOCK_C..1
(5900 -1400);
FORCEPROP 0 LAST CDS_CON_LAST_MODIFIED Fri Aug 25 14:03:17 2023
J 0
(4015 -1385);
PAINT MONO (4015 -1385);
DISPLAY INVISIBLE (4015 -1385);
FORCEPROP 2 LAST CUSTOM_TXT_CDS <XR_PAGE_TITLE>
J 0
(-1990 3850);
DISPLAY 0.638298 (-1990 3850);
PAINT PINK (-1990 3850);
DISPLAY INVISIBLE (-1990 3850);
FORCEPROP 2 LAST CUSTOM_TXT_CDS <Q_NUMBER>
J 0
(4497 -1297);
DISPLAY 1.212766 (4497 -1297);
FORCEPROP 2 LAST CUSTOM_TXT_CDS <CON_PAGE_NUM> OF <CON_TOTAL_PAGES>
J 0
(5454 -1382);
DISPLAY 0.978723 (5454 -1382);
FORCEPROP 2 LAST CUSTOM_TXT_CDS <Q_REV>
J 0
(5716 -1297);
DISPLAY 1.212766 (5716 -1297);
FORCEPROP 2 LAST CUSTOM_TXT_CDS <Q_PROJ>
J 0
(3518 -1298);
DISPLAY 1.212766 (3518 -1298);
FORCEPROP 2 LAST CUSTOM_TXT_CDS <NAME_2>
J 0
(2725 -1350);
FORCEPROP 2 LAST CUSTOM_TXT_CDS <NAME_1>
J 0
(2725 -1225);
FORCEPROP 2 LAST CUSTOM_TXT_CDS <CON_LAST_MODIFIED>
J 0
(4015 -1385);
DISPLAY 0.978723 (4015 -1385);
FORCEPROP 1 LAST Q_TITLE PCH SIDEBAND - ESPI/LPC
J 0
(-3391 -1374);
DISPLAY 2.446809 (-3391 -1374);
PAINT GREEN (-3391 -1374);
FORCEPROP 1 LAST Q_DEPT 
J 1
(2137 -1351);
DISPLAY 1.957447 (2137 -1351);
PAINT GREEN (2137 -1351);
FORCEPROP 2 LAST CDS_XR_PAGE_TITLE CR-202 : @S9S_MB_2U_LIB.S9S_MB_2U(SCH_1):PAGE202
J 0
(-1990 3850);
DISPLAY 0.638298 (-1990 3850);
PAINT PINK (-1990 3850);
DISPLAY INVISIBLE (-1990 3850);
FORCEPROP 2 LAST PAGE_BORDER TRUE
J 0
(-1990 3850);
DISPLAY 0.638298 (-1990 3850);
PAINT PINK (-1990 3850);
DISPLAY INVISIBLE (-1990 3850);
FORCEPROP 1 LAST COMMENT_BODY TRUE
J 0
(5912 -1413);
DISPLAY 0.978723 (5912 -1413);
PAINT GREEN (5912 -1413);
DISPLAY INVISIBLE (5912 -1413);
FORCEPROP 1 LAST CDS_LMAN_SYM_OUTLINE -9475,6775,100,-125
J 0
(5900 -1400);
DISPLAY 0.468085 (5900 -1400);
PAINT GREEN (5900 -1400);
DISPLAY INVISIBLE (5900 -1400);
FORCEPROP 2 LAST CDS_LIB pure_quanta
J 0
(5900 -1400);
PAINT MONO (5900 -1400);
DISPLAY INVISIBLE (5900 -1400);
WIRE 16 -1 (25 1900)(25 1775);
WIRE 16 -1 (1050 2025)(1050 1950);
WIRE 16 -1 (3000 1900)(3000 1775);
WIRE 16 -1 (1400 4600)(1400 4525);
WIRE 16 -1 (1400 3425)(1400 3350);
WIRE 16 -1 (-800 650)(-800 750);
WIRE 16 -1 (625 3550)(625 3850);
WIRE 16 -1 (1875 4125)(1875 4075);
WIRE 16 -1 (1875 4125)(1525 4125);
WIRE 16 -1 (1875 4250)(1875 4125);
WIRE 16 -1 (625 2375)(625 2675);
WIRE 16 -1 (1875 2950)(1875 2900);
WIRE 16 -1 (1875 2950)(1525 2950);
WIRE 16 -1 (1875 3075)(1875 2950);
WIRE 16 -1 (1175 1225)(1175 1300);
WIRE 16 -1 (1050 1650)(1050 1575);
WIRE 16 -1 (575 1050)(575 925);
WIRE 16 -1 (3000 1400)(2000 1400);
FORCEPROP 0 LAST CDS_PHYS_NET_NAME FM_CPU0_SKTOCC_N
J 0
(2190 1448);
PAINT MONO (2190 1448);
DISPLAY INVISIBLE (2190 1448);
FORCEPROP 2 LAST SIG_NAME FM_ESPI_PLD_R_EN_BUF
J 0
(2115 1410);
DISPLAY 0.638298 (2115 1410);
PAINT WHITE (2115 1410);
WIRE 16 -1 (3000 1400)(3000 1575);
WIRE 16 -1 (3250 1400)(3000 1400);
WIRE 16 -1 (3000 1300)(2000 1300);
FORCEPROP 0 LAST CDS_PHYS_NET_NAME FM_CPU0_SKTOCC_N
J 0
(2190 1348);
PAINT MONO (2190 1348);
DISPLAY INVISIBLE (2190 1348);
FORCEPROP 2 LAST SIG_NAME NC_ESPI_PLD_R_EN_BUF
J 0
(2115 1310);
DISPLAY 0.638298 (2115 1310);
PAINT WHITE (2115 1310);
WIRE 16 -1 (1175 1300)(1400 1300);
WIRE 16 -1 (575 1250)(575 1400);
WIRE 16 -1 (1400 1400)(575 1400);
FORCEPROP 2 LAST SIG_NAME FM_ESPI_PLD_R1_EN
J 0
(640 1410);
DISPLAY 0.638298 (640 1410);
PAINT WHITE (640 1410);
WIRE 16 -1 (375 1075)(0 1075);
WIRE 16 -1 (375 1400)(375 1075);
WIRE 16 -1 (575 1400)(375 1400);
WIRE 16 -1 (-400 1400)(25 1400);
FORCEPROP 0 LAST CDS_PHYS_NET_NAME FM_CPU0_SKTOCC_N
J 0
(-210 1448);
PAINT MONO (-210 1448);
DISPLAY INVISIBLE (-210 1448);
WIRE 16 -1 (25 1400)(375 1400);
WIRE 16 -1 (25 1575)(25 1400);
WIRE 16 -1 (1050 1950)(1050 1850);
WIRE 16 -1 (1050 1950)(1175 1950);
WIRE 16 -1 (1175 1500)(1400 1500);
WIRE 16 -1 (1175 1500)(1175 1950);
WIRE 16 -1 (3725 -50)(-550 -50);
FORCEPROP 0 LAST CDS_PHYS_NET_NAME ESPI_LAD0_DATA_IO3
J 0
(2575 -8);
PAINT MONO (2575 -8);
DISPLAY INVISIBLE (2575 -8);
FORCEPROP 0 LAST SIG_NAME ESPI_LPC_LAD0_IO3
J 0
(3015 -40);
DISPLAY 0.553191 (3015 -40);
PAINT WHITE (3015 -40);
WIRE 16 -1 (3725 -100)(-550 -100);
FORCEPROP 0 LAST CDS_PHYS_NET_NAME ESPI_LAD0_DATA_IO3
J 0
(2575 -58);
PAINT MONO (2575 -58);
DISPLAY INVISIBLE (2575 -58);
FORCEPROP 0 LAST SIG_NAME ESPI_LPC_LAD0_IO2
J 0
(3015 -90);
DISPLAY 0.553191 (3015 -90);
PAINT WHITE (3015 -90);
WIRE 16 -1 (2375 2725)(1300 2725);
FORCEPROP 0 LAST CDS_PHYS_NET_NAME FM_CPU0_SKTOCC_N
J 0
(1490 2773);
PAINT MONO (1490 2773);
DISPLAY INVISIBLE (1490 2773);
WIRE 16 -1 (2700 2725)(2375 2725);
WIRE 16 -1 (2375 3900)(1300 3900);
FORCEPROP 0 LAST CDS_PHYS_NET_NAME FM_CPU0_SKTOCC_N
J 0
(1490 3948);
PAINT MONO (1490 3948);
DISPLAY INVISIBLE (1490 3948);
FORCEPROP 2 LAST SIG_NAME FM_ESPI_PLD_EN
J 0
(1490 3910);
DISPLAY 0.638298 (1490 3910);
PAINT WHITE (1490 3910);
WIRE 16 -1 (2375 3900)(2375 2725);
WIRE 16 -1 (2900 2725)(4125 2725);
FORCEPROP 0 LAST CDS_PHYS_NET_NAME FM_CPU0_SKTOCC_N
J 0
(3090 2773);
PAINT MONO (3090 2773);
DISPLAY INVISIBLE (3090 2773);
FORCEPROP 2 LAST SIG_NAME FM_ESPI_PLD_R_EN_BUF
J 0
(3390 2735);
DISPLAY 0.638298 (3390 2735);
PAINT WHITE (3390 2735);
WIRE 16 -1 (1400 2675)(1300 2675);
WIRE 16 -1 (1400 3350)(1400 2675);
WIRE 16 -1 (1525 3275)(1525 3350);
WIRE 16 -1 (1525 3350)(1400 3350);
WIRE 16 -1 (1875 3275)(1875 3350);
WIRE 16 -1 (1875 3350)(1525 3350);
WIRE 16 -1 (4450 3800)(2900 3800);
FORCEPROP 0 LAST CDS_PHYS_NET_NAME FM_CPU0_SKTOCC_N
J 0
(3090 3848);
PAINT MONO (3090 3848);
DISPLAY INVISIBLE (3090 3848);
FORCEPROP 2 LAST SIG_NAME IRQ_ESPI_LPC_SERIRQ_ALERT_R_N
J 0
(3390 3810);
DISPLAY 0.638298 (3390 3810);
PAINT WHITE (3390 3810);
WIRE 16 -1 (2200 2625)(1300 2625);
FORCEPROP 0 LAST CDS_PHYS_NET_NAME FM_CPU0_SKTOCC_N
J 0
(1490 2673);
PAINT MONO (1490 2673);
DISPLAY INVISIBLE (1490 2673);
FORCEPROP 2 LAST SIG_NAME ESPI_BMC_LPC_RST_N
J 0
(1490 2635);
DISPLAY 0.638298 (1490 2635);
PAINT WHITE (1490 2635);
WIRE 16 2175 (-725 325)(25 325);
WIRE 16 2175 (25 325)(25 175);
WIRE 16 2175 (-725 325)(-725 175);
WIRE 16 2175 (-725 175)(25 175);
WIRE 16 -1 (3725 -150)(-550 -150);
FORCEPROP 0 LAST CDS_PHYS_NET_NAME ESPI_LAD0_DATA_IO3
J 0
(2575 -108);
PAINT MONO (2575 -108);
DISPLAY INVISIBLE (2575 -108);
FORCEPROP 0 LAST SIG_NAME ESPI_LPC_LAD0_IO1
J 0
(3015 -140);
DISPLAY 0.553191 (3015 -140);
PAINT WHITE (3015 -140);
WIRE 16 -1 (-200 1075)(-1150 1075);
FORCEPROP 0 LAST $PNN JTAG_TRC_PCH_PTI<6>
J 0
(-960 1170);
DISPLAY INVISIBLE (-960 1170);
FORCEPROP 0 LAST CDS_PHYS_NET_NAME JTAG_TRC_PCH_PTI<6>
J 0
(-960 1123);
PAINT MONO (-960 1123);
DISPLAY INVISIBLE (-960 1123);
FORCEPROP 2 LAST SIG_NAME JTAG_TRC_PCH_PTI<6>
J 0
(-1060 1085);
DISPLAY 0.638298 (-1060 1085);
PAINT WHITE (-1060 1085);
WIRE 16 -1 (-350 225)(1200 225);
FORCEPROP 0 LAST CDS_PHYS_NET_NAME ESPI_LAD0_DATA_IO3
J 0
(-325 267);
PAINT MONO (-325 267);
DISPLAY INVISIBLE (-325 267);
FORCEPROP 0 LAST SIG_NAME ESPI_HOST_LPC_BMC_LFRAME_N
J 0
(375 235);
DISPLAY 0.553191 (375 235);
PAINT WHITE (375 235);
WIRE 16 -1 (-525 2725)(700 2725);
FORCEPROP 0 LAST CDS_PHYS_NET_NAME IRQ_LPC_SERIRQ_ESPI_CS1_N
J 0
(-335 2773);
PAINT MONO (-335 2773);
DISPLAY INVISIBLE (-335 2773);
FORCEPROP 2 LAST SIG_NAME RST_ESPI_RESET_N_R
J 0
(-10 2735);
DISPLAY 0.638298 (-10 2735);
PAINT WHITE (-10 2735);
WIRE 16 -1 (-1675 225)(-800 225);
FORCEPROP 0 LAST CDS_PHYS_NET_NAME ESPI_LAD0_DATA_IO0
J 0
(-1650 267);
PAINT MONO (-1650 267);
DISPLAY INVISIBLE (-1650 267);
FORCEPROP 0 LAST SIG_NAME ESPI_LFRAME_N_BMC_CS0_N
J 0
(-1550 235);
DISPLAY 0.553191 (-1550 235);
PAINT WHITE (-1550 235);
WIRE 16 -1 (-800 225)(-550 225);
WIRE 16 -1 (-800 450)(-800 225);
WIRE 16 -1 (2700 3800)(1300 3800);
FORCEPROP 0 LAST CDS_PHYS_NET_NAME FM_CPU0_SKTOCC_N
J 0
(1490 3848);
PAINT MONO (1490 3848);
DISPLAY INVISIBLE (1490 3848);
FORCEPROP 2 LAST SIG_NAME IRQ_ESPI_LPC_SERIRQ_ALERT_N
J 0
(1490 3810);
DISPLAY 0.638298 (1490 3810);
PAINT WHITE (1490 3810);
WIRE 16 2175 (-925 2825)(-175 2825);
WIRE 16 2175 (-175 2825)(-175 2675);
WIRE 16 2175 (-925 2825)(-925 2675);
WIRE 16 2175 (-925 2675)(-175 2675);
WIRE 16 -1 (-1650 2725)(-725 2725);
FORCEPROP 0 LAST CDS_PHYS_NET_NAME IRQ_LPC_SERIRQ_ESPI_CS1_N
J 0
(-1460 2773);
PAINT MONO (-1460 2773);
DISPLAY INVISIBLE (-1460 2773);
FORCEPROP 2 LAST SIG_NAME RST_ESPI_RESET_N
J 0
(-1560 2735);
DISPLAY 0.638298 (-1560 2735);
PAINT WHITE (-1560 2735);
WIRE 16 -1 (-525 2625)(700 2625);
FORCEPROP 0 LAST CDS_PHYS_NET_NAME IRQ_LPC_SERIRQ_ESPI_CS1_N
J 0
(-335 2673);
PAINT MONO (-335 2673);
DISPLAY INVISIBLE (-335 2673);
FORCEPROP 2 LAST SIG_NAME RST_PLTRST_B_MUX_N
J 0
(-10 2635);
DISPLAY 0.638298 (-10 2635);
PAINT WHITE (-10 2635);
WIRE 16 -1 (625 2675)(700 2675);
FORCEPROP 0 LAST CDS_PHYS_NET_NAME P3V3_AUX
J 0
(675 2722);
PAINT MONO (675 2722);
DISPLAY INVISIBLE (675 2722);
FORCEPROP 0 LAST VOLTAGE 3.3
J 0
(675 2675);
PAINT MONO (675 2675);
DISPLAY INVISIBLE (675 2675);
FORCEPROP 0 LAST $PHYS_NET_NAME P3V3_AUX
J 0
(675 2769);
PAINT MONO (675 2769);
DISPLAY INVISIBLE (675 2769);
WIRE 16 2175 (-875 3875)(-350 3875);
WIRE 16 2175 (-350 3875)(-350 3725);
WIRE 16 2175 (-875 3875)(-875 3725);
WIRE 16 2175 (-875 3725)(-350 3725);
WIRE 16 -1 (-725 3900)(-1950 3900);
FORCEPROP 0 LAST CDS_PHYS_NET_NAME JTAG_CPU1_MUX_GTL_TDO
J 0
(-1760 3948);
PAINT MONO (-1760 3948);
DISPLAY INVISIBLE (-1760 3948);
FORCEPROP 2 LAST SIG_NAME IRQ_LPC_PIRQA_N_ESPI_ALERT0_N
J 0
(-1860 3910);
DISPLAY 0.638298 (-1860 3910);
PAINT WHITE (-1860 3910);
WIRE 16 -1 (-725 3800)(-1950 3800);
FORCEPROP 0 LAST CDS_PHYS_NET_NAME IRQ_LPC_SERIRQ_ESPI_CS1_N
J 0
(-1785 3848);
PAINT MONO (-1785 3848);
DISPLAY INVISIBLE (-1785 3848);
FORCEPROP 2 LAST SIG_NAME IRQ_LPC_SERIRQ_ESPI_CS1_N
J 0
(-1860 3810);
DISPLAY 0.638298 (-1860 3810);
PAINT WHITE (-1860 3810);
WIRE 16 -1 (-525 3800)(700 3800);
FORCEPROP 0 LAST CDS_PHYS_NET_NAME IRQ_LPC_SERIRQ_ESPI_CS1_N
J 0
(-335 3848);
PAINT MONO (-335 3848);
DISPLAY INVISIBLE (-335 3848);
FORCEPROP 2 LAST SIG_NAME IRQ_LPC_SERIRQ_ESPI_CS1_R_N
J 0
(-335 3810);
DISPLAY 0.638298 (-335 3810);
PAINT WHITE (-335 3810);
WIRE 16 -1 (700 3900)(-525 3900);
FORCEPROP 0 LAST CDS_PHYS_NET_NAME JTAG_CPU1_MUX_GTL_TDO
J 0
(-335 3948);
PAINT MONO (-335 3948);
DISPLAY INVISIBLE (-335 3948);
FORCEPROP 2 LAST SIG_NAME IRQ_LPC_PIRQA_N_ESPI_ALERT0_R_N
J 0
(-335 3910);
DISPLAY 0.638298 (-335 3910);
PAINT WHITE (-335 3910);
WIRE 16 -1 (1400 3850)(1300 3850);
WIRE 16 -1 (1400 4525)(1400 3850);
WIRE 16 -1 (1525 4525)(1400 4525);
WIRE 16 -1 (1525 4450)(1525 4525);
WIRE 16 -1 (1875 4450)(1875 4525);
WIRE 16 -1 (1875 4525)(1525 4525);
WIRE 16 -1 (3725 -250)(-550 -250);
FORCEPROP 0 LAST CDS_PHYS_NET_NAME ESPI_LAD0_DATA_IO3
J 0
(2575 -208);
PAINT MONO (2575 -208);
DISPLAY INVISIBLE (2575 -208);
FORCEPROP 0 LAST SIG_NAME ESPI_HOST_LPC_BMC_CLK
J 0
(3015 -240);
DISPLAY 0.553191 (3015 -240);
PAINT WHITE (3015 -240);
WIRE 16 -1 (3725 -200)(-550 -200);
FORCEPROP 0 LAST CDS_PHYS_NET_NAME ESPI_LAD0_DATA_IO3
J 0
(2575 -158);
PAINT MONO (2575 -158);
DISPLAY INVISIBLE (2575 -158);
FORCEPROP 0 LAST SIG_NAME ESPI_LPC_LAD0_IO0
J 0
(3015 -190);
DISPLAY 0.553191 (3015 -190);
PAINT WHITE (3015 -190);
WIRE 16 2175 (-925 -275)(-175 -275);
WIRE 16 2175 (-175 25)(-175 -275);
WIRE 16 2175 (-925 25)(-925 -275);
WIRE 16 2175 (-925 25)(-175 25);
WIRE 16 -1 (-750 -150)(-1650 -150);
FORCEPROP 0 LAST CDS_PHYS_NET_NAME ESPI_LAD0_DATA_IO1
J 0
(-1625 -108);
PAINT MONO (-1625 -108);
DISPLAY INVISIBLE (-1625 -108);
FORCEPROP 0 LAST SIG_NAME ESPI_LAD0_DATA_IO1
J 0
(-1585 -140);
DISPLAY 0.553191 (-1585 -140);
PAINT WHITE (-1585 -140);
WIRE 16 -1 (1525 4250)(1525 4125);
WIRE 16 -1 (1525 3075)(1525 2950);
WIRE 16 -1 (625 3850)(700 3850);
FORCEPROP 0 LAST CDS_PHYS_NET_NAME P3V3_AUX
J 0
(675 3897);
PAINT MONO (675 3897);
DISPLAY INVISIBLE (675 3897);
FORCEPROP 0 LAST VOLTAGE 3.3
J 0
(675 3850);
PAINT MONO (675 3850);
DISPLAY INVISIBLE (675 3850);
FORCEPROP 0 LAST $PHYS_NET_NAME P3V3_AUX
J 0
(675 3944);
PAINT MONO (675 3944);
DISPLAY INVISIBLE (675 3944);
WIRE 16 -1 (-750 -200)(-1650 -200);
FORCEPROP 0 LAST CDS_PHYS_NET_NAME ESPI_LAD0_DATA_IO0
J 0
(-1625 -158);
PAINT MONO (-1625 -158);
DISPLAY INVISIBLE (-1625 -158);
FORCEPROP 0 LAST SIG_NAME ESPI_LAD0_DATA_IO0
J 0
(-1585 -190);
DISPLAY 0.553191 (-1585 -190);
PAINT WHITE (-1585 -190);
WIRE 16 -1 (-750 -100)(-1650 -100);
FORCEPROP 0 LAST CDS_PHYS_NET_NAME ESPI_LAD0_DATA_IO2
J 0
(-1625 -58);
PAINT MONO (-1625 -58);
DISPLAY INVISIBLE (-1625 -58);
FORCEPROP 0 LAST SIG_NAME ESPI_LAD0_DATA_IO2
J 0
(-1585 -90);
DISPLAY 0.553191 (-1585 -90);
PAINT WHITE (-1585 -90);
WIRE 16 -1 (-750 -50)(-1650 -50);
FORCEPROP 0 LAST CDS_PHYS_NET_NAME ESPI_LAD0_DATA_IO3
J 0
(-1625 -8);
PAINT MONO (-1625 -8);
DISPLAY INVISIBLE (-1625 -8);
FORCEPROP 0 LAST SIG_NAME ESPI_LAD0_DATA_IO3
J 0
(-1585 -40);
DISPLAY 0.553191 (-1585 -40);
PAINT WHITE (-1585 -40);
WIRE 16 -1 (-750 -250)(-1650 -250);
FORCEPROP 0 LAST CDS_PHYS_NET_NAME ESPI_LAD0_DATA_IO0
J 0
(-1625 -208);
PAINT MONO (-1625 -208);
DISPLAY INVISIBLE (-1625 -208);
FORCEPROP 0 LAST SIG_NAME CLK_24M_66M_LPC0_ESPI
J 0
(-1585 -240);
DISPLAY 0.553191 (-1585 -240);
PAINT WHITE (-1585 -240);
DOT 1 (1050 1950);
DOT 1 (25 1400);
DOT 1 (375 1400);
DOT 1 (575 1400);
DOT 1 (1400 3350);
DOT 1 (-800 225);
DOT 1 (2375 2725);
DOT 1 (1525 3350);
DOT 1 (1400 4525);
DOT 1 (1525 4525);
DOT 1 (1875 4125);
DOT 1 (1875 2950);
DOT 1 (3000 1400);
FORCENOTE
20211130 CHANGE TO 10 OHM
(-1075 -400) 0;
DISPLAY LEFT (-1075 -400);
DISPLAY 1.021277 (-1075 -400);
PAINT PINK (-1075 -400);
FORCENOTE
20211130 CHANGE TO 10 OHM
(-1050 3600) 0;
DISPLAY LEFT (-1050 3600);
DISPLAY 1.021277 (-1050 3600);
PAINT PINK (-1050 3600);
FORCENOTE
20211130 CHANGE TO 10 OHM
(-1150 2875) 0;
DISPLAY LEFT (-1150 2875);
DISPLAY 1.021277 (-1150 2875);
PAINT PINK (-1150 2875);
QUIT
